%#################################################################
Title:        Cref Error Report
Design:       baseboard_fab2
Date:         Feb 7 18:40:55 2017
%#################################################################



Warnings in Page : @baseboard_fab2_lib.baseboard_fab2(sch_1):Page21
Signal TP_XDP_CPU0_OBSDATA_A3_MBP5_N at (A 4) is labeled only once in the design.
Signal TP_XDP_CPU0_OBSDATA_A2_MBP4_N at (A 4) is labeled only once in the design.
Signal TP_XDP_CPU0_OBSDATA_A0_MBP2_N at (A 4) is labeled only once in the design.
Signal TP_XDP_CPU0_OBSDATA_A1_MBP3_N at (A 4) is labeled only once in the design.
Signal A_CPU0_MCP01_RBIAS at (A 4) is labeled only once in the design.
Signal H_PM_SYNC_GTL_R1 at (B 2) is labeled only once in the design.
Signal H_PMSYNC_CLK_24M_CPU0 at (B 2) is labeled only once in the design.
Signal TP_CPU0_PROCDIS_G_N at (B 1) is labeled only once in the design.
Signal A_CPU0_ABC_RCOMP0 at (B 4) is labeled only once in the design.
Signal A_CPU0_ABC_RCOMP2 at (B 4) is labeled only once in the design.
Signal A_CPU0_ABC_RCOMP1 at (B 4) is labeled only once in the design.
Signal A_CPU0_DEF_RCOMP2 at (B 4) is labeled only once in the design.
Signal A_CPU0_DEF_RCOMP1 at (B 4) is labeled only once in the design.
Signal A_CPU0_DEF_RCOMP0 at (B 4) is labeled only once in the design.
Signal A_CPU0_PE3_RBIAS at (A 4) is labeled only once in the design.
Signal A_CPU0_PE012_RBIAS at (A 4) is labeled only once in the design.
Signal A_CPU0_UPI2_RBIAS at (A 4) is labeled only once in the design.
Signal A_CPU0_UPI01_RBIAS at (A 4) is labeled only once in the design.
Signal  SVID_DIO1_CPU0 at (B 2) is labeled only once in the design.
Signal  SVID_CLK1_CPU0 at (B 2) is labeled only once in the design.
Signal SVID_ALERT1_CPU0_N at (B 2) is labeled only once in the design.
Signal SVID_ALERT0_CPU0_N at (B 2) is labeled only once in the design.
Signal  SVID_CLK0_CPU0 at (B 2) is labeled only once in the design.
Signal  SVID_DIO0_CPU0 at (B 2) is labeled only once in the design.
Signal     TP_NMI_CPU0 at (A 1) is labeled only once in the design.
Signal TP_CPU0_SOCKET_ID_2 at (B 2) is labeled only once in the design.
Signal  XDP_CPU_MBP0_N at (A 4) has too little display space.

Warnings in Page : @baseboard_fab2_lib.baseboard_fab2(sch_1):Page22
Signal TP_CPU0_RSVD_228 at (B 1) is labeled only once in the design.
Signal TP_CPU0_RSVD_236 at (B 1) is labeled only once in the design.
Signal TP_CPU0_RSVD_233 at (B 1) is labeled only once in the design.
Signal TP_CPU0_RSVD_232 at (B 1) is labeled only once in the design.
Signal TP_CPU0_RSVD_231 at (B 1) is labeled only once in the design.
Signal TP_CPU0_RSVD_256 at (A 4) is labeled only once in the design.
Signal TP_CPU0_RSVD_TEST_11 at (A 4) is labeled only once in the design.
Signal TP_CPU0_RSVD_253 at (A 4) is labeled only once in the design.
Signal TP_CPU0_RSVD_254 at (A 4) is labeled only once in the design.
Signal TP_CPU0_RSVD_303 at (B 4) is labeled only once in the design.
Signal TP_CPU0_RSVD_304 at (B 4) is labeled only once in the design.
Signal TP_CPU0_RSVD_287 at (B 4) is labeled only once in the design.
Signal TP_CPU0_RSVD_286 at (B 4) is labeled only once in the design.
Signal TP_CPU0_RSVD_285 at (B 4) is labeled only once in the design.
Signal TP_CPU0_RSVD_283 at (B 4) is labeled only once in the design.
Signal TP_CPU0_RSVD_284 at (B 4) is labeled only once in the design.
Signal TP_CPU0_RSVD_282 at (B 4) is labeled only once in the design.
Signal TP_CPU0_RSVD_275 at (B 4) is labeled only once in the design.
Signal TP_CPU0_RSVD_267 at (A 4) is labeled only once in the design.
Signal TP_CPU0_RSVD_266 at (A 4) is labeled only once in the design.
Signal TP_CPU0_RSVD_263 at (A 4) is labeled only once in the design.
Signal TP_CPU0_RSVD_261 at (A 4) is labeled only once in the design.
Signal TP_CPU0_RSVD_259 at (A 4) is labeled only once in the design.
Signal TP_CPU0_RSVD_194 at (A 1) is labeled only once in the design.
Signal TP_CPU0_RSVD_198 at (A 1) is labeled only once in the design.
Signal TP_CPU0_RSVD_199 at (A 1) is labeled only once in the design.
Signal TP_CPU0_RSVD_205 at (A 1) is labeled only once in the design.
Signal TP_CPU0_RSVD_204 at (A 1) is labeled only once in the design.
Signal TP_CPU0_RSVD_208 at (A 1) is labeled only once in the design.
Signal TP_CPU0_RSVD_210 at (A 1) is labeled only once in the design.
Signal TP_CPU0_RSVD_211 at (A 1) is labeled only once in the design.
Signal TP_CPU0_RSVD_212 at (A 1) is labeled only once in the design.
Signal TP_CPU0_RSVD_TEST_4 at (B 1) is labeled only once in the design.
Signal TP_CPU0_RSVD_TEST_3 at (B 1) is labeled only once in the design.
Signal PD_CPU0_RSVD_TEST_2 at (B 2) is labeled only once in the design.
Signal PD_CPU0_RSVD_TEST_1 at (B 2) is labeled only once in the design.
Signal TP_CPU0_RSVD_222 at (B 1) is labeled only once in the design.
Signal TP_CPU0_RSVD_223 at (B 1) is labeled only once in the design.
Signal TP_CPU0_RSVD_241 at (B 1) is labeled only once in the design.
Signal TP_CPU0_RSVD_240 at (B 1) is labeled only once in the design.
Signal TP_CPU0_RSVD_239 at (B 1) is labeled only once in the design.
Signal TP_CPU0_RSVD_238 at (B 1) is labeled only once in the design.
Signal TP_CPU0_RSVD_237 at (B 1) is labeled only once in the design.
Signal TP_CPU0_RSVD_235 at (B 1) is labeled only once in the design.
Signal TP_CPU0_RSVD_234 at (B 1) is labeled only once in the design.
Signal TP_CPU0_RSVD_230 at (B 1) is labeled only once in the design.
Signal TP_CPU0_RSVD_229 at (B 1) is labeled only once in the design.
Signal TP_CPU0_RSVD_227 at (B 1) is labeled only once in the design.
Signal TP_CPU0_RSVD_226 at (B 1) is labeled only once in the design.
Signal TP_CPU0_RSVD_225 at (B 1) is labeled only once in the design.
Signal TP_CPU0_RSVD_224 at (B 1) is labeled only once in the design.
Signal TP_CPU0_RSVD_289 at (B 4) is labeled only once in the design.
Signal TP_CPU0_RSVD_288 at (B 4) is labeled only once in the design.
Signal TP_CPU0_RSVD_298 at (B 4) is labeled only once in the design.
Signal TP_CPU0_RSVD_260 at (A 4) is labeled only once in the design.
Signal TP_CPU0_RSVD_270 at (A 4) is labeled only once in the design.
Signal TP_CPU0_RSVD_269 at (A 4) is labeled only once in the design.
Signal TP_CPU0_RSVD_271 at (B 4) is labeled only once in the design.
Signal TP_CPU0_RSVD_273 at (B 4) is labeled only once in the design.
Signal TP_CPU0_RSVD_268 at (A 4) is labeled only once in the design.
Signal TP_CPU0_RSVD_290 at (B 4) is labeled only once in the design.
Signal TP_CPU0_RSVD_291 at (B 4) is labeled only once in the design.
Signal TP_CPU0_RSVD_292 at (B 4) is labeled only once in the design.
Signal TP_CPU0_RSVD_293 at (B 4) is labeled only once in the design.
Signal TP_CPU0_RSVD_274 at (B 4) is labeled only once in the design.
Signal TP_CPU0_RSVD_272 at (B 4) is labeled only once in the design.
Signal TP_CPU0_RSVD_276 at (B 4) is labeled only once in the design.
Signal TP_CPU0_RSVD_278 at (B 4) is labeled only once in the design.
Signal TP_CPU0_RSVD_280 at (B 4) is labeled only once in the design.
Signal TP_CPU0_RSVD_264 at (A 4) is labeled only once in the design.
Signal TP_CPU0_RSVD_262 at (A 4) is labeled only once in the design.
Signal TP_CPU0_RSVD_277 at (B 4) is labeled only once in the design.
Signal TP_CPU0_RSVD_279 at (B 4) is labeled only once in the design.
Signal TP_CPU0_RSVD_281 at (B 4) is labeled only once in the design.
Signal TP_CPU0_RSVD_242 at (A 4) is labeled only once in the design.
Signal TP_CPU0_RSVD_243 at (A 4) is labeled only once in the design.
Signal TP_CPU0_RSVD_244 at (A 4) is labeled only once in the design.
Signal TP_CPU0_RSVD_245 at (A 4) is labeled only once in the design.
Signal TP_CPU0_RSVD_246 at (A 4) is labeled only once in the design.
Signal TP_CPU0_RSVD_247 at (A 4) is labeled only once in the design.
Signal TP_CPU0_RSVD_249 at (A 4) is labeled only once in the design.
Signal TP_CPU0_RSVD_250 at (A 4) is labeled only once in the design.
Signal TP_CPU0_RSVD_251 at (A 4) is labeled only once in the design.
Signal TP_CPU0_RSVD_258 at (A 4) is labeled only once in the design.
Signal TP_CPU0_RSVD_265 at (A 4) is labeled only once in the design.
Signal TP_CPU0_RSVD_252 at (A 4) is labeled only once in the design.
Signal TP_CPU0_RSVD_248 at (A 4) is labeled only once in the design.
Signal TP_CPU0_RSVD_300 at (B 4) is labeled only once in the design.
Signal TP_CPU0_RSVD_214 at (A 1) is labeled only once in the design.
Signal TP_CPU0_RSVD_216 at (A 1) is labeled only once in the design.
Signal TP_CPU0_RSVD_219 at (B 1) is labeled only once in the design.
Signal TP_CPU0_RSVD_TEST_5 at (A 1) is labeled only once in the design.
Signal TP_CPU0_RSVD_218 at (B 1) is labeled only once in the design.
Signal TP_CPU0_RSVD_217 at (B 1) is labeled only once in the design.
Signal TP_CPU0_RSVD_299 at (B 4) is labeled only once in the design.

Warnings in Page : @baseboard_fab2_lib.baseboard_fab2(sch_1):Page29
Signal TP_CPU0_RSVD_182 at (A 4) is labeled only once in the design.
Signal TP_CPU0_RSVD_183 at (A 4) is labeled only once in the design.
Signal TP_CPU0_RSVD_174 at (A 4) is labeled only once in the design.
Signal TP_CPU0_RSVD_175 at (A 4) is labeled only once in the design.
Signal TP_CPU0_RSVD_176 at (A 4) is labeled only once in the design.
Signal TP_CPU0_RSVD_177 at (A 4) is labeled only once in the design.
Signal TP_CPU0_RSVD_178 at (A 4) is labeled only once in the design.
Signal TP_CPU0_RSVD_179 at (A 4) is labeled only once in the design.
Signal TP_CPU0_RSVD_180 at (A 4) is labeled only once in the design.
Signal TP_CPU0_RSVD_181 at (A 4) is labeled only once in the design.
Signal TP_CPU0_RSVD_190 at (A 1) is labeled only once in the design.
Signal TP_CPU0_RSVD_189 at (A 1) is labeled only once in the design.
Signal TP_CPU0_RSVD_186 at (A 1) is labeled only once in the design.
Signal TP_CPU0_RSVD_184 at (A 1) is labeled only once in the design.
Signal TP_CPU0_RSVD_173 at (A 1) is labeled only once in the design.
Signal TP_CPU0_RSVD_172 at (A 1) is labeled only once in the design.

Warnings in Page : @baseboard_fab2_lib.baseboard_fab2(sch_1):Page35
Signal TP_CPU0_UPI2_RSVD_DT21 at (B 2) is labeled only once in the design.
Signal TP_CPU0_UPI2_RSVD_DM21 at (B 2) is labeled only once in the design.
Signal TP_CPU0_UPI2_RSVD_DL20 at (A 2) is labeled only once in the design.
Signal TP_CPU0_UPI2_RSVD_DG20 at (A 2) is labeled only once in the design.
Signal TP_CPU0_UPI2_RSVD_DH19 at (A 2) is labeled only once in the design.
Signal TP_CPU0_UPI2_RSVD_DK17 at (A 2) is labeled only once in the design.
Signal TP_CPU0_UPI2_RSVD_DG18 at (A 2) is labeled only once in the design.
Signal TP_CPU0_UPI2_RSVD_DD17 at (A 2) is labeled only once in the design.
Signal TP_CPU0_UPI2_RSVD_DF15 at (A 2) is labeled only once in the design.
Signal TP_CPU0_UPI2_RSVD_DC16 at (A 2) is labeled only once in the design.
Signal TP_CPU0_UPI2_RSVD_DA16 at (A 2) is labeled only once in the design.
Signal TP_CPU0_UPI2_RSVD_DP21 at (B 2) is labeled only once in the design.
Signal TP_CPU0_UPI2_RSVD_DN20 at (B 2) is labeled only once in the design.
Signal TP_CPU0_UPI2_RSVD_DK19 at (B 2) is labeled only once in the design.
Signal TP_CPU0_UPI2_RSVD_DJ20 at (B 2) is labeled only once in the design.
Signal TP_CPU0_UPI2_RSVD_DJ18 at (B 2) is labeled only once in the design.
Signal TP_CPU0_UPI2_RSVD_DH17 at (B 2) is labeled only once in the design.
Signal TP_CPU0_UPI2_RSVD_DE16 at (B 2) is labeled only once in the design.
Signal TP_CPU0_UPI2_RSVD_DD15 at (B 2) is labeled only once in the design.
Signal TP_CPU0_UPI2_RSVD_DB15 at (B 2) is labeled only once in the design.
Signal TP_CPU0_UPI2_RSVD_CW16 at (B 2) is labeled only once in the design.
Signal TP_CPU0_UPI2_RSVD_CR14 at (B 2) is labeled only once in the design.
Signal TP_CPU0_UPI2_RSVD_CK13 at (B 2) is labeled only once in the design.
Signal TP_CPU0_UPI2_RSVD_CH13 at (B 2) is labeled only once in the design.
Signal TP_CPU0_UPI2_RSVD_CG12 at (B 2) is labeled only once in the design.
Signal TP_CPU0_UPI2_RSVD_CD11 at (B 2) is labeled only once in the design.
Signal TP_CPU0_UPI2_RSVD_CB11 at (B 2) is labeled only once in the design.
Signal TP_CPU0_UPI2_RSVD_CA12 at (B 2) is labeled only once in the design.
Signal TP_CPU0_UPI2_RSVD_CW14 at (A 2) is labeled only once in the design.
Signal TP_CPU0_UPI2_RSVD_CU14 at (A 2) is labeled only once in the design.
Signal TP_CPU0_UPI2_RSVD_CM13 at (A 2) is labeled only once in the design.
Signal TP_CPU0_UPI2_RSVD_CJ14 at (A 2) is labeled only once in the design.
Signal TP_CPU0_UPI2_RSVD_CF13 at (A 2) is labeled only once in the design.
Signal TP_CPU0_UPI2_RSVD_CH11 at (A 2) is labeled only once in the design.
Signal TP_CPU0_UPI2_RSVD_CE12 at (A 2) is labeled only once in the design.
Signal TP_CPU0_UPI2_RSVD_CC10 at (A 2) is labeled only once in the design.
Signal TP_CPU0_UPI2_RSVD_CC12 at (A 2) is labeled only once in the design.
Signal TP_CPU0_UPI2_RSVD_CF11 at (B 2) is labeled only once in the design.
Signal TP_CPU0_UPI2_RSVD_CV13 at (B 2) is labeled only once in the design.
Signal TP_CPU0_UPI2_RSVD_DF17 at (B 2) is labeled only once in the design.

Warnings in Page : @baseboard_fab2_lib.baseboard_fab2(sch_1):Page36
Signal TP_CPU0_RSVD_144 at (A 4) is labeled only once in the design.
Signal TP_CPU0_RSVD_150 at (B 4) is labeled only once in the design.
Signal TP_CPU0_RSVD_154 at (B 4) is labeled only once in the design.
Signal TP_CPU0_RSVD_149 at (B 4) is labeled only once in the design.
Signal TP_CPU0_RSVD_148 at (B 4) is labeled only once in the design.
Signal TP_CPU0_RSVD_147 at (B 4) is labeled only once in the design.
Signal TP_CPU0_RSVD_146 at (A 4) is labeled only once in the design.
Signal TP_CPU0_RSVD_145 at (A 4) is labeled only once in the design.
Signal TP_CPU0_RSVD_152 at (B 4) is labeled only once in the design.
Signal TP_CPU0_RSVD_151 at (B 4) is labeled only once in the design.
Signal TP_CPU0_RSVD_124 at (B 3) is labeled only once in the design.
Signal TP_CPU0_RSVD_82 at (A 1) is labeled only once in the design.
Signal TP_CPU0_RSVD_113 at (B 3) is labeled only once in the design.
Signal TP_CPU0_RSVD_155 at (B 4) is labeled only once in the design.
Signal TP_CPU0_RSVD_156 at (B 4) is labeled only once in the design.
Signal TP_CPU0_RSVD_157 at (B 4) is labeled only once in the design.
Signal TP_CPU0_RSVD_158 at (B 4) is labeled only once in the design.
Signal TP_CPU0_RSVD_159 at (B 4) is labeled only once in the design.
Signal TP_CPU0_RSVD_160 at (B 4) is labeled only once in the design.
Signal TP_CPU0_RSVD_161 at (B 4) is labeled only once in the design.
Signal TP_CPU0_RSVD_162 at (B 4) is labeled only once in the design.
Signal TP_CPU0_RSVD_163 at (B 4) is labeled only once in the design.
Signal TP_CPU0_RSVD_164 at (B 4) is labeled only once in the design.
Signal TP_CPU0_RSVD_166 at (B 4) is labeled only once in the design.
Signal TP_CPU0_RSVD_167 at (B 4) is labeled only once in the design.
Signal TP_CPU0_RSVD_168 at (B 4) is labeled only once in the design.
Signal TP_CPU0_RSVD_169 at (B 4) is labeled only once in the design.
Signal TP_CPU0_RSVD_170 at (B 4) is labeled only once in the design.
Signal TP_CPU0_RSVD_171 at (B 4) is labeled only once in the design.
Signal TP_CPU0_RSVD_255 at (A 3) is labeled only once in the design.
Signal TP_CPU0_RSVD_94 at (A 3) is labeled only once in the design.
Signal TP_CPU0_RSVD_95 at (A 3) is labeled only once in the design.
Signal TP_CPU0_RSVD_97 at (A 3) is labeled only once in the design.
Signal TP_CPU0_RSVD_99 at (A 3) is labeled only once in the design.
Signal TP_CPU0_RSVD_100 at (A 3) is labeled only once in the design.
Signal TP_CPU0_RSVD_101 at (A 3) is labeled only once in the design.
Signal TP_CPU0_RSVD_105 at (B 3) is labeled only once in the design.
Signal TP_CPU0_RSVD_106 at (B 3) is labeled only once in the design.
Signal TP_CPU0_RSVD_108 at (B 3) is labeled only once in the design.
Signal TP_CPU0_RSVD_111 at (B 3) is labeled only once in the design.
Signal TP_CPU0_RSVD_114 at (B 3) is labeled only once in the design.
Signal TP_CPU0_RSVD_117 at (B 3) is labeled only once in the design.
Signal TP_CPU0_RSVD_119 at (B 3) is labeled only once in the design.
Signal TP_CPU0_RSVD_121 at (B 3) is labeled only once in the design.
Signal TP_CPU0_RSVD_123 at (B 3) is labeled only once in the design.
Signal  TP_CPU0_TEST_9 at (B 1) is labeled only once in the design.
Signal  TP_CPU0_TEST_8 at (B 1) is labeled only once in the design.
Signal  TP_CPU0_TEST_7 at (B 1) is labeled only once in the design.
Signal  TP_CPU0_TEST_6 at (B 1) is labeled only once in the design.
Signal TP_CPU0_TEST_10 at (B 1) is labeled only once in the design.
Signal TP_CPU0_RSVD_85 at (A 1) is labeled only once in the design.
Signal TP_CPU0_RSVD_90 at (B 1) is labeled only once in the design.
Signal TP_CPU0_RSVD_91 at (B 1) is labeled only once in the design.

Warnings in Page : @baseboard_fab2_lib.baseboard_fab2(sch_1):Page37
Signal VSENSE_VCCINR2PMAX_CPU0 at (A 1) is labeled only once in the design.
Signal VSENSE_PMAX_CPU0 at (A 1) is labeled only once in the design.

Warnings in Page : @baseboard_fab2_lib.baseboard_fab2(sch_1):Page39
Signal TP_CPU0_RSVD_32 at (B 2) is labeled only once in the design.
Signal TP_CPU0_RSVD_33 at (B 2) is labeled only once in the design.
Signal TP_CPU0_RSVD_34 at (B 2) is labeled only once in the design.
Signal TP_CPU0_RSVD_61 at (A 4) is labeled only once in the design.
Signal TP_CPU0_KTI2_DFX_DN at (A 4) is labeled only once in the design.
Signal TP_CPU0_RSVD_64 at (A 4) is labeled only once in the design.
Signal TP_CPU0_RSVD_66 at (A 4) is labeled only once in the design.
Signal TP_CPU0_RSVD_67 at (A 4) is labeled only once in the design.
Signal TP_CPU0_RSVD_69 at (A 4) is labeled only once in the design.
Signal TP_CPU0_RSVD_70 at (A 4) is labeled only once in the design.
Signal TP_CPU0_RSVD_72 at (A 4) is labeled only once in the design.
Signal TP_CPU0_RSVD_73 at (A 4) is labeled only once in the design.
Signal TP_CPU0_KTI2_AMONV at (B 4) is labeled only once in the design.
Signal TP_CPU0_RSVD_13 at (A 2) is labeled only once in the design.
Signal TP_CPU0_RSVD_43 at (B 2) is labeled only once in the design.
Signal  TP_CPU0_RSVD_0 at (A 2) is labeled only once in the design.
Signal  TP_CPU0_RSVD_1 at (A 2) is labeled only once in the design.
Signal  TP_CPU0_RSVD_2 at (A 2) is labeled only once in the design.
Signal  TP_CPU0_RSVD_3 at (A 2) is labeled only once in the design.
Signal  TP_CPU0_RSVD_4 at (A 2) is labeled only once in the design.
Signal  TP_CPU0_RSVD_5 at (A 2) is labeled only once in the design.
Signal  TP_CPU0_RSVD_6 at (A 2) is labeled only once in the design.
Signal  TP_CPU0_RSVD_7 at (A 2) is labeled only once in the design.
Signal  TP_CPU0_RSVD_8 at (A 2) is labeled only once in the design.
Signal  TP_CPU0_RSVD_9 at (A 2) is labeled only once in the design.
Signal TP_CPU0_RSVD_10 at (A 2) is labeled only once in the design.
Signal TP_CPU0_RSVD_11 at (A 2) is labeled only once in the design.
Signal TP_CPU0_RSVD_12 at (A 2) is labeled only once in the design.
Signal TP_CPU0_RSVD_14 at (A 2) is labeled only once in the design.
Signal TP_CPU0_RSVD_15 at (A 2) is labeled only once in the design.
Signal TP_CPU0_RSVD_16 at (A 2) is labeled only once in the design.
Signal TP_CPU0_RSVD_17 at (A 2) is labeled only once in the design.
Signal TP_CPU0_RSVD_18 at (A 2) is labeled only once in the design.
Signal TP_CPU0_RSVD_19 at (A 2) is labeled only once in the design.
Signal TP_CPU0_RSVD_20 at (A 2) is labeled only once in the design.
Signal TP_CPU0_RSVD_21 at (A 2) is labeled only once in the design.
Signal TP_CPU0_RSVD_22 at (A 2) is labeled only once in the design.
Signal TP_CPU0_RSVD_23 at (A 2) is labeled only once in the design.
Signal TP_CPU0_RSVD_24 at (A 2) is labeled only once in the design.
Signal TP_CPU0_RSVD_25 at (A 2) is labeled only once in the design.
Signal TP_CPU0_RSVD_26 at (A 2) is labeled only once in the design.
Signal TP_CPU0_RSVD_27 at (A 2) is labeled only once in the design.
Signal TP_CPU0_RSVD_28 at (A 2) is labeled only once in the design.
Signal TP_CPU0_RSVD_29 at (A 2) is labeled only once in the design.
Signal TP_CPU0_RSVD_30 at (A 2) is labeled only once in the design.
Signal TP_CPU0_RSVD_31 at (B 2) is labeled only once in the design.
Signal TP_CPU0_RSVD_35 at (B 2) is labeled only once in the design.
Signal TP_CPU0_RSVD_36 at (B 2) is labeled only once in the design.
Signal TP_CPU0_RSVD_37 at (B 2) is labeled only once in the design.
Signal TP_CPU0_RSVD_38 at (B 2) is labeled only once in the design.
Signal TP_CPU0_RSVD_39 at (B 2) is labeled only once in the design.
Signal TP_CPU0_RSVD_40 at (B 2) is labeled only once in the design.
Signal TP_CPU0_RSVD_41 at (B 2) is labeled only once in the design.
Signal TP_CPU0_RSVD_42 at (B 2) is labeled only once in the design.
Signal TP_CPU0_RSVD_44 at (B 2) is labeled only once in the design.
Signal TP_CPU0_RSVD_45 at (B 2) is labeled only once in the design.
Signal TP_CPU0_RSVD_46 at (B 2) is labeled only once in the design.
Signal TP_CPU0_RSVD_47 at (B 2) is labeled only once in the design.
Signal TP_CPU0_RSVD_49 at (B 2) is labeled only once in the design.
Signal TP_CPU0_RSVD_50 at (B 2) is labeled only once in the design.
Signal TP_CPU0_RSVD_51 at (B 2) is labeled only once in the design.
Signal TP_CPU0_RSVD_53 at (B 2) is labeled only once in the design.
Signal TP_CPU0_RSVD_54 at (B 2) is labeled only once in the design.
Signal TP_CPU0_RSVD_55 at (B 2) is labeled only once in the design.
Signal TP_CPU0_RSVD_56 at (B 2) is labeled only once in the design.
Signal TP_CPU0_RSVD_57 at (B 2) is labeled only once in the design.
Signal TP_CPU0_RSVD_59 at (B 2) is labeled only once in the design.
Signal TP_CPU0_RSVD_60 at (B 2) is labeled only once in the design.
Signal TP_CPU0_RSVD_48 at (B 2) is labeled only once in the design.

Warnings in Page : @baseboard_fab2_lib.baseboard_fab2(sch_1):Page43
Signal TP_CH_A_DIMM_A0_RFU_2 at (A 4) is labeled only once in the design.
Signal TP_CH_A_DIMM_A0_RFU_0 at (A 4) is labeled only once in the design.
Signal TP_CH_A_DIMM_A0_RFU_1 at (A 4) is labeled only once in the design.

Warnings in Page : @baseboard_fab2_lib.baseboard_fab2(sch_1):Page44
Signal TP_CH_A_DIMM_A1_RFU_1 at (A 4) is labeled only once in the design.
Signal TP_CH_A_DIMM_A1_RFU_2 at (A 4) is labeled only once in the design.
Signal TP_CH_A_DIMM_A1_RFU_0 at (A 4) is labeled only once in the design.

Warnings in Page : @baseboard_fab2_lib.baseboard_fab2(sch_1):Page45
Signal TP_CH_B_DIMM_B0_RFU_1 at (A 4) is labeled only once in the design.
Signal TP_CH_B_DIMM_B0_RFU_0 at (A 4) is labeled only once in the design.
Signal TP_CH_B_DIMM_B0_RFU_2 at (A 4) is labeled only once in the design.

Warnings in Page : @baseboard_fab2_lib.baseboard_fab2(sch_1):Page46
Signal TP_CH_B_DIMM_B1_RFU_1 at (A 4) is labeled only once in the design.
Signal TP_CH_B_DIMM_B1_RFU_0 at (A 4) is labeled only once in the design.
Signal TP_CH_B_DIMM_B1_RFU_2 at (A 4) is labeled only once in the design.

Warnings in Page : @baseboard_fab2_lib.baseboard_fab2(sch_1):Page47
Signal TP_CH_C_DIMM_C0_RFU_1 at (A 4) is labeled only once in the design.
Signal TP_CH_C_DIMM_C0_RFU_0 at (A 4) is labeled only once in the design.
Signal TP_CH_C_DIMM_C0_RFU_2 at (A 4) is labeled only once in the design.

Warnings in Page : @baseboard_fab2_lib.baseboard_fab2(sch_1):Page48
Signal TP_CH_C_DIMM_C1_RFU_1 at (A 4) is labeled only once in the design.
Signal TP_CH_C_DIMM_C1_RFU_0 at (A 4) is labeled only once in the design.
Signal TP_CH_C_DIMM_C1_RFU_2 at (A 4) is labeled only once in the design.

Warnings in Page : @baseboard_fab2_lib.baseboard_fab2(sch_1):Page49
Signal TP_CH_D_DIMM_D0_RFU_2 at (A 4) is labeled only once in the design.
Signal TP_CH_D_DIMM_D0_RFU_1 at (A 4) is labeled only once in the design.
Signal TP_CH_D_DIMM_D0_RFU_0 at (A 4) is labeled only once in the design.

Warnings in Page : @baseboard_fab2_lib.baseboard_fab2(sch_1):Page50
Signal TP_CH_D_DIMM_D1_RFU_1 at (A 4) is labeled only once in the design.
Signal TP_CH_D_DIMM_D1_RFU_2 at (A 4) is labeled only once in the design.
Signal TP_CH_D_DIMM_D1_RFU_0 at (A 4) is labeled only once in the design.

Warnings in Page : @baseboard_fab2_lib.baseboard_fab2(sch_1):Page51
Signal TP_CH_E_DIMM_E0_RFU_1 at (A 4) is labeled only once in the design.
Signal TP_CH_E_DIMM_E0_RFU_2 at (A 4) is labeled only once in the design.
Signal TP_CH_E_DIMM_E0_RFU_0 at (A 4) is labeled only once in the design.

Warnings in Page : @baseboard_fab2_lib.baseboard_fab2(sch_1):Page52
Signal TP_CH_E_DIMM_E1_RFU_1 at (A 4) is labeled only once in the design.
Signal TP_CH_E_DIMM_E1_RFU_0 at (A 4) is labeled only once in the design.
Signal TP_CH_E_DIMM_E1_RFU_2 at (A 4) is labeled only once in the design.

Warnings in Page : @baseboard_fab2_lib.baseboard_fab2(sch_1):Page53
Signal TP_CH_F_DIMM_F0_RFU_1 at (A 4) is labeled only once in the design.
Signal TP_CH_F_DIMM_F0_RFU_0 at (A 4) is labeled only once in the design.
Signal TP_CH_F_DIMM_F0_RFU_2 at (A 4) is labeled only once in the design.

Warnings in Page : @baseboard_fab2_lib.baseboard_fab2(sch_1):Page54
Signal TP_CH_F_DIMM_F1_RFU_1 at (A 4) is labeled only once in the design.
Signal TP_CH_F_DIMM_F1_RFU_0 at (A 4) is labeled only once in the design.
Signal TP_CH_F_DIMM_F1_RFU_2 at (A 4) is labeled only once in the design.

Warnings in Page : @baseboard_fab2_lib.baseboard_fab2(sch_1):Page55
Signal TP_CPU1_SOCKET_ID_2 at (B 2) is labeled only once in the design.
Signal  SVID_DIO1_CPU1 at (B 2) is labeled only once in the design.
Signal  SVID_CLK1_CPU1 at (B 2) is labeled only once in the design.
Signal SVID_ALERT1_CPU1_N at (B 2) is labeled only once in the design.
Signal  SVID_DIO0_CPU1 at (B 2) is labeled only once in the design.
Signal  SVID_CLK0_CPU1 at (B 2) is labeled only once in the design.
Signal SVID_ALERT0_CPU1_N at (B 2) is labeled only once in the design.
Signal H_PM_SYNC_GTL_R2 at (B 2) is labeled only once in the design.
Signal H_PMSYNC_CLK_24M_CPU1 at (B 2) is labeled only once in the design.
Signal A_CPU1_GHJ_RCOMP2 at (B 4) is labeled only once in the design.
Signal A_CPU1_GHJ_RCOMP0 at (B 4) is labeled only once in the design.
Signal A_CPU1_KLM_RCOMP1 at (B 4) is labeled only once in the design.
Signal A_CPU1_KLM_RCOMP0 at (B 4) is labeled only once in the design.
Signal A_CPU1_PE3_RBIAS at (A 4) is labeled only once in the design.
Signal A_CPU1_PE012_RBIAS at (A 4) is labeled only once in the design.
Signal A_CPU1_UPI01_RBIAS at (A 4) is labeled only once in the design.
Signal A_CPU1_UPI2_RBIAS at (A 4) is labeled only once in the design.
Signal TP_XDP_CPU1_OBSDATA_B1_MBP3_N at (A 4) is labeled only once in the design.
Signal TP_XDP_CPU1_OBSDATA_B0_MBP2_N at (A 4) is labeled only once in the design.
Signal A_CPU1_KLM_RCOMP2 at (B 4) is labeled only once in the design.
Signal A_CPU1_GHJ_RCOMP1 at (B 4) is labeled only once in the design.
Signal TP_XDP_CPU1_OBSDATA_B3_MBP5_N at (A 4) is labeled only once in the design.
Signal TP_XDP_CPU1_OBSDATA_B2_MBP4_N at (A 4) is labeled only once in the design.
Signal A_CPU1_MCP01_RBIAS at (A 4) is labeled only once in the design.
Signal TP_CPU1_PROC_DIS_G_N at (B 2) is labeled only once in the design.
Signal     TP_CPU1_NMI at (A 1) is labeled only once in the design.
Signal SMB_PIROM_CPU1_SDA at (A 4) has too little display space.

Warnings in Page : @baseboard_fab2_lib.baseboard_fab2(sch_1):Page56
Signal TP_CPU1_RSVD_228 at (B 1) is labeled only once in the design.
Signal TP_CPU1_RSVD_218 at (B 1) is labeled only once in the design.
Signal TP_CPU1_RSVD_219 at (B 1) is labeled only once in the design.
Signal TP_CPU1_RSVD_TEST_4 at (B 1) is labeled only once in the design.
Signal TP_CPU1_RSVD_204 at (A 1) is labeled only once in the design.
Signal PD_CPU1_RSVD_TEST_2 at (B 2) is labeled only once in the design.
Signal PD_CPU1_RSVD_TEST_1 at (B 2) is labeled only once in the design.
Signal TP_CPU1_RSVD_290 at (B 4) is labeled only once in the design.
Signal TP_CPU1_RSVD_288 at (B 4) is labeled only once in the design.
Signal TP_CPU1_RSVD_287 at (B 4) is labeled only once in the design.
Signal TP_CPU1_RSVD_286 at (B 4) is labeled only once in the design.
Signal TP_CPU1_RSVD_285 at (B 4) is labeled only once in the design.
Signal TP_CPU1_RSVD_254 at (A 4) is labeled only once in the design.
Signal TP_CPU1_RSVD_263 at (A 4) is labeled only once in the design.
Signal TP_CPU1_RSVD_264 at (A 4) is labeled only once in the design.
Signal TP_CPU1_RSVD_277 at (B 4) is labeled only once in the design.
Signal TP_CPU1_RSVD_214 at (A 1) is labeled only once in the design.
Signal TP_CPU1_RSVD_208 at (A 1) is labeled only once in the design.
Signal TP_CPU1_RSVD_194 at (A 1) is labeled only once in the design.
Signal TP_CPU1_RSVD_198 at (A 1) is labeled only once in the design.
Signal TP_CPU1_RSVD_210 at (A 1) is labeled only once in the design.
Signal TP_CPU1_RSVD_216 at (A 1) is labeled only once in the design.
Signal TP_CPU1_RSVD_TEST_5 at (A 1) is labeled only once in the design.
Signal TP_CPU1_RSVD_TEST_3 at (B 1) is labeled only once in the design.
Signal TP_CPU1_RSVD_222 at (B 1) is labeled only once in the design.
Signal TP_CPU1_RSVD_224 at (B 1) is labeled only once in the design.
Signal TP_CPU1_RSVD_225 at (B 1) is labeled only once in the design.
Signal TP_CPU1_RSVD_223 at (B 1) is labeled only once in the design.
Signal TP_CPU1_RSVD_240 at (B 1) is labeled only once in the design.
Signal TP_CPU1_RSVD_239 at (B 1) is labeled only once in the design.
Signal TP_CPU1_RSVD_238 at (B 1) is labeled only once in the design.
Signal TP_CPU1_RSVD_237 at (B 1) is labeled only once in the design.
Signal TP_CPU1_RSVD_231 at (B 1) is labeled only once in the design.
Signal TP_CPU1_RSVD_232 at (B 1) is labeled only once in the design.
Signal TP_CPU1_RSVD_233 at (B 1) is labeled only once in the design.
Signal TP_CPU1_RSVD_199 at (A 1) is labeled only once in the design.
Signal TP_CPU1_RSVD_304 at (B 4) is labeled only once in the design.
Signal TP_CPU1_RSVD_274 at (B 4) is labeled only once in the design.
Signal TP_CPU1_RSVD_268 at (A 4) is labeled only once in the design.
Signal TP_CPU1_RSVD_251 at (A 4) is labeled only once in the design.
Signal TP_CPU1_RSVD_250 at (A 4) is labeled only once in the design.
Signal TP_CPU1_RSVD_249 at (A 4) is labeled only once in the design.
Signal TP_CPU1_RSVD_248 at (A 4) is labeled only once in the design.
Signal TP_CPU1_RSVD_247 at (A 4) is labeled only once in the design.
Signal TP_CPU1_RSVD_246 at (A 4) is labeled only once in the design.
Signal TP_CPU1_RSVD_245 at (A 4) is labeled only once in the design.
Signal TP_CPU1_RSVD_244 at (A 4) is labeled only once in the design.
Signal TP_CPU1_RSVD_283 at (B 4) is labeled only once in the design.
Signal TP_CPU1_RSVD_282 at (B 4) is labeled only once in the design.
Signal TP_CPU1_RSVD_252 at (A 4) is labeled only once in the design.
Signal TP_CPU1_RSVD_273 at (B 4) is labeled only once in the design.
Signal TP_CPU1_RSVD_272 at (B 4) is labeled only once in the design.
Signal TP_CPU1_RSVD_271 at (B 4) is labeled only once in the design.
Signal TP_CPU1_RSVD_269 at (A 4) is labeled only once in the design.
Signal TP_CPU1_RSVD_298 at (B 4) is labeled only once in the design.
Signal TP_CPU1_RSVD_242 at (A 4) is labeled only once in the design.
Signal TP_CPU1_RSVD_243 at (A 4) is labeled only once in the design.
Signal TP_CPU1_RSVD_260 at (A 4) is labeled only once in the design.
Signal TP_CPU1_RSVD_261 at (A 4) is labeled only once in the design.
Signal TP_CPU1_RSVD_262 at (A 4) is labeled only once in the design.
Signal TP_CPU1_RSVD_266 at (A 4) is labeled only once in the design.
Signal TP_CPU1_RSVD_267 at (A 4) is labeled only once in the design.
Signal TP_CPU1_RSVD_270 at (A 4) is labeled only once in the design.
Signal TP_CPU1_RSVD_284 at (B 4) is labeled only once in the design.
Signal TP_CPU1_RSVD_289 at (B 4) is labeled only once in the design.
Signal TP_CPU1_RSVD_291 at (B 4) is labeled only once in the design.
Signal TP_CPU1_RSVD_293 at (B 4) is labeled only once in the design.
Signal TP_CPU1_RSVD_292 at (B 4) is labeled only once in the design.
Signal TP_CPU1_RSVD_253 at (A 4) is labeled only once in the design.
Signal TP_CPU1_RSVD_TEST_11 at (A 4) is labeled only once in the design.
Signal TP_CPU1_RSVD_259 at (A 4) is labeled only once in the design.
Signal TP_CPU1_RSVD_258 at (A 4) is labeled only once in the design.
Signal TP_CPU1_RSVD_256 at (A 4) is labeled only once in the design.
Signal TP_CPU1_RSVD_265 at (A 4) is labeled only once in the design.
Signal TP_CPU1_RSVD_281 at (B 4) is labeled only once in the design.
Signal TP_CPU1_RSVD_280 at (B 4) is labeled only once in the design.
Signal TP_CPU1_RSVD_279 at (B 4) is labeled only once in the design.
Signal TP_CPU1_RSVD_278 at (B 4) is labeled only once in the design.
Signal TP_CPU1_RSVD_276 at (B 4) is labeled only once in the design.
Signal TP_CPU1_RSVD_275 at (B 4) is labeled only once in the design.
Signal TP_CPU1_RSVD_303 at (B 4) is labeled only once in the design.
Signal TP_CPU1_RSVD_300 at (B 4) is labeled only once in the design.
Signal TP_CPU1_RSVD_212 at (A 1) is labeled only once in the design.
Signal TP_CPU1_RSVD_211 at (A 1) is labeled only once in the design.
Signal TP_CPU1_RSVD_226 at (B 1) is labeled only once in the design.
Signal TP_CPU1_RSVD_227 at (B 1) is labeled only once in the design.
Signal TP_CPU1_RSVD_229 at (B 1) is labeled only once in the design.
Signal TP_CPU1_RSVD_230 at (B 1) is labeled only once in the design.
Signal TP_CPU1_RSVD_234 at (B 1) is labeled only once in the design.
Signal TP_CPU1_RSVD_235 at (B 1) is labeled only once in the design.
Signal TP_CPU1_RSVD_236 at (B 1) is labeled only once in the design.
Signal TP_CPU1_RSVD_241 at (B 1) is labeled only once in the design.
Signal TP_CPU1_RSVD_205 at (A 1) is labeled only once in the design.
Signal TP_CPU1_RSVD_217 at (B 1) is labeled only once in the design.
Signal TP_CPU1_RSVD_299 at (B 4) is labeled only once in the design.

Warnings in Page : @baseboard_fab2_lib.baseboard_fab2(sch_1):Page63
Signal TP_CPU1_DMI_RX_DP1 at (B 4) is labeled only once in the design.
Signal TP_CPU1_DMI_RX_DN3 at (B 4) is labeled only once in the design.
Signal TP_CPU1_DMI_RX_DN0 at (B 4) is labeled only once in the design.
Signal TP_IRQ_CPU1_CD_HFI0_N at (B 4) is labeled only once in the design.
Signal TP_CPU1_RSVD_183 at (A 4) is labeled only once in the design.
Signal TP_CPU1_RSVD_180 at (A 4) is labeled only once in the design.
Signal TP_CPU1_RSVD_179 at (A 4) is labeled only once in the design.
Signal TP_CPU1_RSVD_177 at (A 4) is labeled only once in the design.
Signal TP_CPU1_RSVD_175 at (A 4) is labeled only once in the design.
Signal TP_CPU1_RSVD_174 at (A 4) is labeled only once in the design.
Signal TP_CPU1_RSVD_176 at (A 4) is labeled only once in the design.
Signal TP_CPU1_RSVD_182 at (A 4) is labeled only once in the design.
Signal TP_CPU1_RSVD_178 at (A 4) is labeled only once in the design.
Signal TP_CPU1_RSVD_181 at (A 4) is labeled only once in the design.
Signal TP_CPU1_DMI_RX_DN1 at (B 4) is labeled only once in the design.
Signal TP_CPU1_DMI_RX_DN2 at (B 4) is labeled only once in the design.
Signal TP_CPU1_DMI_RX_DP3 at (B 4) is labeled only once in the design.
Signal TP_CPU1_DMI_RX_DP2 at (B 4) is labeled only once in the design.
Signal TP_SMB_CPU1_CD_HFI0_I2CDAT at (A 4) is labeled only once in the design.
Signal TP_SMB_CPU1_CD_HFI0_I2CCLK at (B 4) is labeled only once in the design.
Signal TP_LED_CPU1_CD_HFI0_N at (B 4) is labeled only once in the design.
Signal TP_RST_CPU1_CD_HFI0_N at (B 4) is labeled only once in the design.
Signal TP_FM_CPU1_CD_HFI0_MODPRST_N at (B 4) is labeled only once in the design.
Signal TP_CPU1_RSVD_172 at (A 2) is labeled only once in the design.
Signal TP_CPU1_RSVD_173 at (A 2) is labeled only once in the design.
Signal TP_CPU1_RSVD_184 at (A 2) is labeled only once in the design.
Signal TP_CPU1_RSVD_186 at (A 2) is labeled only once in the design.
Signal TP_CPU1_RSVD_189 at (A 2) is labeled only once in the design.
Signal TP_CPU1_RSVD_190 at (A 2) is labeled only once in the design.
Signal TP_CD_HFI1_CPU1_I2CDAT at (A 2) is labeled only once in the design.
Signal TP_CD_HFI1_CPU1_I2CLK at (B 2) is labeled only once in the design.
Signal TP_CD_HFI1_CPU1_INT_N at (B 2) is labeled only once in the design.
Signal TP_CD_HFI1_CPU1_LED_N at (B 2) is labeled only once in the design.
Signal TP_CD_HFI1_CPU1_MODPRST_N at (B 2) is labeled only once in the design.
Signal TP_CD_HFI1_CPU1_RESET_N at (B 2) is labeled only once in the design.
Signal TP_CPU1_DMI_TX_DP3 at (B 2) is labeled only once in the design.
Signal TP_CPU1_DMI_TX_DP2 at (B 2) is labeled only once in the design.
Signal TP_CPU1_DMI_TX_DP1 at (B 2) is labeled only once in the design.
Signal TP_CPU1_DMI_TX_DP0 at (B 2) is labeled only once in the design.
Signal TP_CPU1_DMI_TX_DN3 at (B 2) is labeled only once in the design.
Signal TP_CPU1_DMI_TX_DN2 at (B 2) is labeled only once in the design.
Signal TP_CPU1_DMI_TX_DN1 at (B 2) is labeled only once in the design.
Signal TP_CPU1_DMI_TX_DN0 at (B 2) is labeled only once in the design.
Signal TP_CPU1_DMI_RX_DP0 at (B 4) is labeled only once in the design.

Warnings in Page : @baseboard_fab2_lib.baseboard_fab2(sch_1):Page64
Signal TP_P3E_CPU1_PE1_RSR3_TXN<15:8> at (B 1) is labeled only once in the design.
Signal TP_P3E_CPU1_PE1_MP_TXN<7:0> at (A 1) is labeled only once in the design.
Signal TP_P3E_CPU1_PE1_RSR3_TXP<15:8> at (B 1) is labeled only once in the design.
Signal TP_P3E_CPU1_PE1_MP_TXP<7:0> at (A 1) is labeled only once in the design.
Signal TP_P3E_CPU1_PE1_RSR3_RXN<15:8> at (B 4) is labeled only once in the design.
Signal TP_P3E_CPU1_PE1_MP_RXN<7:0> at (A 4) is labeled only once in the design.
Signal TP_P3E_CPU1_PE1_RSR3_RXP<15:8> at (B 4) is labeled only once in the design.
Signal TP_P3E_CPU1_PE1_MP_RXP<7:0> at (A 4) is labeled only once in the design.

Warnings in Page : @baseboard_fab2_lib.baseboard_fab2(sch_1):Page65
Signal TP_P3E_CPU1_PE2_RSR_TXN<15:0> at (B 1) is labeled only once in the design.
Signal TP_P3E_CPU1_PE2_RSR_TXP<15:0> at (B 1) is labeled only once in the design.
Signal TP_P3E_CPU1_PE2_RSR_RXN<15:0> at (B 4) is labeled only once in the design.
Signal TP_P3E_CPU1_PE2_RSR_RXP<15:0> at (B 4) is labeled only once in the design.

Warnings in Page : @baseboard_fab2_lib.baseboard_fab2(sch_1):Page69
Signal TP_CPU1_UPI2_RSVD_CR14 at (B 2) is labeled only once in the design.
Signal TP_CPU1_UPI2_RSVD_CC12 at (A 2) is labeled only once in the design.
Signal TP_CPU1_UPI2_RSVD_CC10 at (A 2) is labeled only once in the design.
Signal TP_CPU1_UPI2_RSVD_CE12 at (A 2) is labeled only once in the design.
Signal TP_CPU1_UPI2_RSVD_CH11 at (A 2) is labeled only once in the design.
Signal TP_CPU1_UPI2_RSVD_CF13 at (A 2) is labeled only once in the design.
Signal TP_CPU1_UPI2_RSVD_CJ14 at (A 2) is labeled only once in the design.
Signal TP_CPU1_UPI2_RSVD_CM13 at (A 2) is labeled only once in the design.
Signal TP_CPU1_UPI2_RSVD_CA12 at (B 2) is labeled only once in the design.
Signal TP_CPU1_UPI2_RSVD_CB11 at (B 2) is labeled only once in the design.
Signal TP_CPU1_UPI2_RSVD_CD11 at (B 2) is labeled only once in the design.
Signal TP_CPU1_UPI2_RSVD_CF11 at (B 2) is labeled only once in the design.
Signal TP_CPU1_UPI2_RSVD_CG12 at (B 2) is labeled only once in the design.
Signal TP_CPU1_UPI2_RSVD_CH13 at (B 2) is labeled only once in the design.
Signal TP_CPU1_UPI2_RSVD_CK13 at (B 2) is labeled only once in the design.
Signal TP_CPU1_UPI2_RSVD_CV13 at (B 2) is labeled only once in the design.
Signal TP_CPU1_UPI2_RSVD_CW16 at (B 2) is labeled only once in the design.
Signal TP_CPU1_UPI2_RSVD_DB15 at (B 2) is labeled only once in the design.
Signal TP_CPU1_UPI2_RSVD_DD15 at (B 2) is labeled only once in the design.
Signal TP_CPU1_UPI2_RSVD_DF17 at (B 2) is labeled only once in the design.
Signal TP_CPU1_UPI2_RSVD_DH17 at (B 2) is labeled only once in the design.
Signal TP_CPU1_UPI2_RSVD_DJ18 at (B 2) is labeled only once in the design.
Signal TP_CPU1_UPI2_RSVD_DJ20 at (B 2) is labeled only once in the design.
Signal TP_CPU1_UPI2_RSVD_DK19 at (B 2) is labeled only once in the design.
Signal TP_CPU1_UPI2_RSVD_DN20 at (B 2) is labeled only once in the design.
Signal TP_CPU1_UPI2_RSVD_DP21 at (B 2) is labeled only once in the design.
Signal TP_CPU1_UPI2_RSVD_CU14 at (A 2) is labeled only once in the design.
Signal TP_CPU1_UPI2_RSVD_CW14 at (A 2) is labeled only once in the design.
Signal TP_CPU1_UPI2_RSVD_DA16 at (A 2) is labeled only once in the design.
Signal TP_CPU1_UPI2_RSVD_DC16 at (A 2) is labeled only once in the design.
Signal TP_CPU1_UPI2_RSVD_DF15 at (A 2) is labeled only once in the design.
Signal TP_CPU1_UPI2_RSVD_DD17 at (A 2) is labeled only once in the design.
Signal TP_CPU1_UPI2_RSVD_DG18 at (A 2) is labeled only once in the design.
Signal TP_CPU1_UPI2_RSVD_DK17 at (A 2) is labeled only once in the design.
Signal TP_CPU1_UPI2_RSVD_DH19 at (A 2) is labeled only once in the design.
Signal TP_CPU1_UPI2_RSVD_DG20 at (B 2) is labeled only once in the design.
Signal TP_CPU1_UPI2_RSVD_DL20 at (B 2) is labeled only once in the design.
Signal TP_CPU1_UPI2_RSVD_DM21 at (B 2) is labeled only once in the design.
Signal TP_CPU1_UPI2_RSVD_DT21 at (B 2) is labeled only once in the design.
Signal TP_CPU1_UPI2_RSVD_DE16 at (B 2) is labeled only once in the design.

Warnings in Page : @baseboard_fab2_lib.baseboard_fab2(sch_1):Page70
Signal TP_CPU1_RSVD_149 at (B 4) is labeled only once in the design.
Signal TP_CPU1_RSVD_148 at (B 4) is labeled only once in the design.
Signal TP_CPU1_RSVD_144 at (A 4) is labeled only once in the design.
Signal TP_CPU1_RSVD_145 at (A 4) is labeled only once in the design.
Signal TP_CPU1_RSVD_146 at (A 4) is labeled only once in the design.
Signal TP_CPU1_RSVD_147 at (A 4) is labeled only once in the design.
Signal TP_CPU1_RSVD_150 at (B 4) is labeled only once in the design.
Signal TP_CPU1_RSVD_152 at (B 4) is labeled only once in the design.
Signal TP_CPU1_RSVD_151 at (B 4) is labeled only once in the design.
Signal TP_CPU1_RSVD_154 at (B 4) is labeled only once in the design.
Signal TP_CPU1_RSVD_255 at (A 3) is labeled only once in the design.
Signal TP_CPU1_RSVD_171 at (B 4) is labeled only once in the design.
Signal TP_CPU1_RSVD_170 at (B 4) is labeled only once in the design.
Signal TP_CPU1_RSVD_169 at (B 4) is labeled only once in the design.
Signal TP_CPU1_RSVD_168 at (B 4) is labeled only once in the design.
Signal TP_CPU1_RSVD_167 at (B 4) is labeled only once in the design.
Signal TP_CPU1_RSVD_166 at (B 4) is labeled only once in the design.
Signal TP_CPU1_RSVD_164 at (B 4) is labeled only once in the design.
Signal TP_CPU1_RSVD_163 at (B 4) is labeled only once in the design.
Signal TP_CPU1_RSVD_162 at (B 4) is labeled only once in the design.
Signal TP_CPU1_RSVD_161 at (B 4) is labeled only once in the design.
Signal TP_CPU1_RSVD_160 at (B 4) is labeled only once in the design.
Signal TP_CPU1_RSVD_159 at (B 4) is labeled only once in the design.
Signal TP_CPU1_RSVD_158 at (B 4) is labeled only once in the design.
Signal TP_CPU1_RSVD_157 at (B 4) is labeled only once in the design.
Signal TP_CPU1_RSVD_156 at (B 4) is labeled only once in the design.
Signal TP_CPU1_RSVD_155 at (B 4) is labeled only once in the design.
Signal TP_CPU1_RSVD_124 at (B 3) is labeled only once in the design.
Signal TP_CPU1_RSVD_123 at (B 3) is labeled only once in the design.
Signal TP_CPU1_RSVD_121 at (B 3) is labeled only once in the design.
Signal TP_CPU1_RSVD_119 at (B 3) is labeled only once in the design.
Signal TP_CPU1_RSVD_117 at (B 3) is labeled only once in the design.
Signal TP_CPU1_RSVD_114 at (B 3) is labeled only once in the design.
Signal TP_CPU1_RSVD_113 at (B 3) is labeled only once in the design.
Signal TP_CPU1_RSVD_106 at (B 3) is labeled only once in the design.
Signal TP_CPU1_RSVD_105 at (B 3) is labeled only once in the design.
Signal TP_CPU1_RSVD_101 at (A 3) is labeled only once in the design.
Signal TP_CPU1_RSVD_100 at (A 3) is labeled only once in the design.
Signal TP_CPU1_RSVD_99 at (A 3) is labeled only once in the design.
Signal TP_CPU1_RSVD_97 at (A 3) is labeled only once in the design.
Signal TP_CPU1_RSVD_95 at (A 3) is labeled only once in the design.
Signal TP_CPU1_RSVD_94 at (A 3) is labeled only once in the design.
Signal  TP_CPU1_TEST_9 at (B 1) is labeled only once in the design.
Signal  TP_CPU1_TEST_8 at (B 1) is labeled only once in the design.
Signal  TP_CPU1_TEST_7 at (B 1) is labeled only once in the design.
Signal  TP_CPU1_TEST_6 at (B 1) is labeled only once in the design.
Signal TP_CPU1_TEST_10 at (B 1) is labeled only once in the design.
Signal TP_CPU1_RSVD_82 at (A 1) is labeled only once in the design.
Signal TP_CPU1_RSVD_85 at (A 1) is labeled only once in the design.
Signal TP_CPU1_RSVD_90 at (B 1) is labeled only once in the design.
Signal TP_CPU1_RSVD_91 at (B 1) is labeled only once in the design.
Signal TP_CPU1_RSVD_108 at (B 3) is labeled only once in the design.
Signal TP_CPU1_RSVD_111 at (B 3) is labeled only once in the design.

Warnings in Page : @baseboard_fab2_lib.baseboard_fab2(sch_1):Page71
Signal VSENSE_PMAX_CPU1 at (A 1) is labeled only once in the design.
Signal VSENSE_VCCINR2PMAX_CPU1 at (A 1) is labeled only once in the design.

Warnings in Page : @baseboard_fab2_lib.baseboard_fab2(sch_1):Page73
Signal TP_CPU1_KTI2_AMONV at (B 3) is labeled only once in the design.
Signal TP_CPU1_RSVD_43 at (B 2) is labeled only once in the design.
Signal TP_CPU1_RSVD_61 at (A 3) is labeled only once in the design.
Signal TP_CPU1_KTI2_DFX_DN at (A 3) is labeled only once in the design.
Signal TP_CPU1_RSVD_64 at (A 3) is labeled only once in the design.
Signal TP_CPU1_RSVD_66 at (A 3) is labeled only once in the design.
Signal TP_CPU1_RSVD_67 at (A 3) is labeled only once in the design.
Signal TP_CPU1_RSVD_69 at (A 3) is labeled only once in the design.
Signal TP_CPU1_RSVD_70 at (A 3) is labeled only once in the design.
Signal TP_CPU1_RSVD_72 at (A 3) is labeled only once in the design.
Signal TP_CPU1_RSVD_73 at (A 3) is labeled only once in the design.
Signal  TP_CPU1_RSVD_0 at (A 2) is labeled only once in the design.
Signal  TP_CPU1_RSVD_1 at (A 2) is labeled only once in the design.
Signal  TP_CPU1_RSVD_2 at (A 2) is labeled only once in the design.
Signal  TP_CPU1_RSVD_3 at (A 2) is labeled only once in the design.
Signal  TP_CPU1_RSVD_4 at (A 2) is labeled only once in the design.
Signal  TP_CPU1_RSVD_5 at (A 2) is labeled only once in the design.
Signal  TP_CPU1_RSVD_6 at (A 2) is labeled only once in the design.
Signal  TP_CPU1_RSVD_7 at (A 2) is labeled only once in the design.
Signal  TP_CPU1_RSVD_8 at (A 2) is labeled only once in the design.
Signal  TP_CPU1_RSVD_9 at (A 2) is labeled only once in the design.
Signal TP_CPU1_RSVD_10 at (A 2) is labeled only once in the design.
Signal TP_CPU1_RSVD_11 at (A 2) is labeled only once in the design.
Signal TP_CPU1_RSVD_12 at (A 2) is labeled only once in the design.
Signal TP_CPU1_RSVD_13 at (A 2) is labeled only once in the design.
Signal TP_CPU1_RSVD_14 at (A 2) is labeled only once in the design.
Signal TP_CPU1_RSVD_15 at (A 2) is labeled only once in the design.
Signal TP_CPU1_RSVD_16 at (A 2) is labeled only once in the design.
Signal TP_CPU1_RSVD_17 at (A 2) is labeled only once in the design.
Signal TP_CPU1_RSVD_18 at (A 2) is labeled only once in the design.
Signal TP_CPU1_RSVD_19 at (A 2) is labeled only once in the design.
Signal TP_CPU1_RSVD_20 at (A 2) is labeled only once in the design.
Signal TP_CPU1_RSVD_21 at (A 2) is labeled only once in the design.
Signal TP_CPU1_RSVD_22 at (A 2) is labeled only once in the design.
Signal TP_CPU1_RSVD_23 at (A 2) is labeled only once in the design.
Signal TP_CPU1_RSVD_24 at (A 2) is labeled only once in the design.
Signal TP_CPU1_RSVD_25 at (A 2) is labeled only once in the design.
Signal TP_CPU1_RSVD_26 at (A 2) is labeled only once in the design.
Signal TP_CPU1_RSVD_27 at (A 2) is labeled only once in the design.
Signal TP_CPU1_RSVD_28 at (A 2) is labeled only once in the design.
Signal TP_CPU1_RSVD_29 at (A 2) is labeled only once in the design.
Signal TP_CPU1_RSVD_30 at (A 2) is labeled only once in the design.
Signal TP_CPU1_RSVD_31 at (B 2) is labeled only once in the design.
Signal TP_CPU1_RSVD_32 at (B 2) is labeled only once in the design.
Signal TP_CPU1_RSVD_33 at (B 2) is labeled only once in the design.
Signal TP_CPU1_RSVD_34 at (B 2) is labeled only once in the design.
Signal TP_CPU1_RSVD_35 at (B 2) is labeled only once in the design.
Signal TP_CPU1_RSVD_36 at (B 2) is labeled only once in the design.
Signal TP_CPU1_RSVD_37 at (B 2) is labeled only once in the design.
Signal TP_CPU1_RSVD_38 at (B 2) is labeled only once in the design.
Signal TP_CPU1_RSVD_39 at (B 2) is labeled only once in the design.
Signal TP_CPU1_RSVD_40 at (B 2) is labeled only once in the design.
Signal TP_CPU1_RSVD_41 at (B 2) is labeled only once in the design.
Signal TP_CPU1_RSVD_42 at (B 2) is labeled only once in the design.
Signal TP_CPU1_RSVD_44 at (B 2) is labeled only once in the design.
Signal TP_CPU1_RSVD_45 at (B 2) is labeled only once in the design.
Signal TP_CPU1_RSVD_46 at (B 2) is labeled only once in the design.
Signal TP_CPU1_RSVD_47 at (B 2) is labeled only once in the design.
Signal TP_CPU1_RSVD_49 at (B 2) is labeled only once in the design.
Signal TP_CPU1_RSVD_50 at (B 2) is labeled only once in the design.
Signal TP_CPU1_RSVD_51 at (B 2) is labeled only once in the design.
Signal TP_CPU1_RSVD_53 at (B 2) is labeled only once in the design.
Signal TP_CPU1_RSVD_54 at (B 2) is labeled only once in the design.
Signal TP_CPU1_RSVD_55 at (B 2) is labeled only once in the design.
Signal TP_CPU1_RSVD_56 at (B 2) is labeled only once in the design.
Signal TP_CPU1_RSVD_57 at (B 2) is labeled only once in the design.
Signal TP_CPU1_RSVD_59 at (B 2) is labeled only once in the design.
Signal TP_CPU1_RSVD_60 at (B 2) is labeled only once in the design.
Signal TP_CPU1_RSVD_48 at (B 2) is labeled only once in the design.

Warnings in Page : @baseboard_fab2_lib.baseboard_fab2(sch_1):Page77
Signal TP_CH_G_DIMM_G0_RFU_1 at (A 4) is labeled only once in the design.
Signal TP_CH_G_DIMM_G0_RFU_2 at (A 4) is labeled only once in the design.
Signal TP_CH_G_DIMM_G0_RFU_0 at (A 4) is labeled only once in the design.

Warnings in Page : @baseboard_fab2_lib.baseboard_fab2(sch_1):Page78
Signal TP_CH_G_DIMM0_RFU_2 at (A 4) is labeled only once in the design.
Signal TP_CH_G_DIMM0_RFU_0 at (A 4) is labeled only once in the design.
Signal TP_CH_G_DIMM0_RFU_1 at (A 4) is labeled only once in the design.

Warnings in Page : @baseboard_fab2_lib.baseboard_fab2(sch_1):Page79
Signal TP_CH_H_DIMM_H0_RFU_1 at (A 4) is labeled only once in the design.
Signal TP_CH_H_DIMM_H0_RFU_0 at (A 4) is labeled only once in the design.
Signal TP_CH_H_DIMM_H0_RFU_2 at (A 4) is labeled only once in the design.

Warnings in Page : @baseboard_fab2_lib.baseboard_fab2(sch_1):Page80
Signal TP_CH_H_DIMM0_RFU_0 at (A 4) is labeled only once in the design.
Signal TP_CH_H_DIMM0_RFU_1 at (A 4) is labeled only once in the design.
Signal TP_CH_H_DIMM0_RFU_2 at (A 4) is labeled only once in the design.

Warnings in Page : @baseboard_fab2_lib.baseboard_fab2(sch_1):Page81
Signal TP_CH_J_DIMM_J0_RFU_1 at (A 4) is labeled only once in the design.
Signal TP_CH_J_DIMM_J0_RFU_0 at (A 4) is labeled only once in the design.
Signal TP_CH_J_DIMM_J0_RFU_2 at (A 4) is labeled only once in the design.

Warnings in Page : @baseboard_fab2_lib.baseboard_fab2(sch_1):Page82
Signal TP_CH_J_DIMM_J1_RFU_1 at (A 4) is labeled only once in the design.
Signal TP_CH_J_DIMM_J1_RFU_0 at (A 4) is labeled only once in the design.
Signal TP_CH_J_DIMM_J1_RFU_2 at (A 4) is labeled only once in the design.

Warnings in Page : @baseboard_fab2_lib.baseboard_fab2(sch_1):Page83
Signal TP_CH_K_DIMM_K0_RFU_1 at (A 4) is labeled only once in the design.
Signal TP_CH_K_DIMM_K0_RFU_0 at (A 4) is labeled only once in the design.
Signal TP_CH_K_DIMM_K0_RFU_2 at (A 4) is labeled only once in the design.

Warnings in Page : @baseboard_fab2_lib.baseboard_fab2(sch_1):Page84
Signal TP_CH_K_DIMM0_RFU_2 at (A 4) is labeled only once in the design.
Signal TP_CH_K_DIMM0_RFU_0 at (A 4) is labeled only once in the design.
Signal TP_CH_K_DIMM0_RFU_1 at (A 4) is labeled only once in the design.

Warnings in Page : @baseboard_fab2_lib.baseboard_fab2(sch_1):Page85
Signal TP_CH_L_DIMM_L0_RFU_2 at (A 4) is labeled only once in the design.
Signal TP_CH_L_DIMM_L0_RFU_0 at (A 4) is labeled only once in the design.
Signal TP_CH_L_DIMM_L0_RFU_1 at (A 4) is labeled only once in the design.

Warnings in Page : @baseboard_fab2_lib.baseboard_fab2(sch_1):Page86
Signal TP_CH_L_DIMM0_RFU_1 at (A 4) is labeled only once in the design.
Signal TP_CH_L_DIMM0_RFU_0 at (A 4) is labeled only once in the design.
Signal TP_CH_L_DIMM0_RFU_2 at (A 4) is labeled only once in the design.

Warnings in Page : @baseboard_fab2_lib.baseboard_fab2(sch_1):Page87
Signal TP_CH_M_DIMM_M0_RFU_1 at (A 4) is labeled only once in the design.
Signal TP_CH_M_DIMM_M0_RFU_0 at (A 4) is labeled only once in the design.
Signal TP_CH_M_DIMM_M0_RFU_2 at (A 4) is labeled only once in the design.

Warnings in Page : @baseboard_fab2_lib.baseboard_fab2(sch_1):Page88
Signal TP_CH_M_DIMM_M1_RFU_1 at (A 4) is labeled only once in the design.
Signal TP_CH_M_DIMM_M1_RFU_0 at (A 4) is labeled only once in the design.
Signal TP_CH_M_DIMM_M1_RFU_2 at (A 4) is labeled only once in the design.

Warnings in Page : @baseboard_fab2_lib.baseboard_fab2(sch_1):Page89
Signal FM_ADR_COMPLETE_CPU0_R at (B 3) is labeled only once in the design.
Signal IRQ_DIMM_SAVE_N at (B 3) is labeled only once in the design.
Signal FM_ADR_COMPLETE_R at (B 4) is labeled only once in the design.
Signal FM_ADR_COMPLETE_CPU1_R at (A 3) is labeled only once in the design.
Signal IRQ_DIMM_SAVE_LVT3 at (B 2) is labeled only once in the design.
Signal IRQ_DIMM_SAVE_LVT3_CPU1 at (B 2) is labeled only once in the design.
Signal IRQ_DIMM_SAVE_CPU1_R_N at (A 2) is labeled only once in the design.
Signal IRQ_DIMM_SAVE_R_N at (B 2) is labeled only once in the design.
Signal FM_ADR_COMPLETE_CPU1_N at (A 3) is labeled only once in the design.

Warnings in Page : @baseboard_fab2_lib.baseboard_fab2(sch_1):Page91
Signal TP_HFI_IO_CONN0_RSVD_17 at (B 4) is labeled only once in the design.

Warnings in Page : @baseboard_fab2_lib.baseboard_fab2(sch_1):Page92
Signal P0V7_GTL2104_VREF_0 at (A 2) is labeled only once in the design.
Signal PWRGD_CPUPWRGD_R1 at (B 2) is labeled only once in the design.
Signal FM_CPU_CATERR_LVT3_R2_N at (B 2) is labeled only once in the design.
Signal FM_CPU1_THERMTRIP_LVT3_R_N at (B 2) is labeled only once in the design.
Signal PD_GTL2104_DIR_1 at (B 2) is labeled only once in the design.
Signal H_CPU_ERR2_G_R_N at (A 4) is labeled only once in the design.
Signal  H_CPU_MSMI_G_N at (A 3) is labeled only once in the design.
Signal H_CPU_ERR2_GTL_N at (A 3) is labeled only once in the design.
Signal FM_CPU0_THERMTRIP_LVT3_R_N at (A 2) is labeled only once in the design.
Signal FM_CPU_ERR2_LVT3_R_N at (A 2) is labeled only once in the design.
Signal FM_CPU_MSMI_LVT3_R_N at (A 2) is labeled only once in the design.
Signal FM_CPU0_FIVR_FAULT_R_LVT3 at (A 2) is labeled only once in the design.
Signal FM_CPU1_FIVR_FAULT_R_LVT3 at (B 2) is labeled only once in the design.
Signal H_CPU_CATERR_G_N at (B 3) is labeled only once in the design.
Signal P0V7_GTL2104_VREF_1 at (B 2) is labeled only once in the design.
Signal PD_GTL2104_DIR_0 at (A 2) is labeled only once in the design.

Warnings in Page : @baseboard_fab2_lib.baseboard_fab2(sch_1):Page93
Signal FM_CPU1_PROCHOT_LVT3_K_N at (B 2) is labeled only once in the design.
Signal FM_CPU0_PROCHOT_LVT3_K_N at (B 2) is labeled only once in the design.
Signal H_CPU1_PROCHOT_G_PCH_N at (A 3) is labeled only once in the design.
Signal FM_CPU_ERR0_LVT3_R_N at (B 2) is labeled only once in the design.
Signal FM_CPU0_PROCHOT_LVT3_R_N at (B 2) is labeled only once in the design.
Signal FM_CPU1_PROCHOT_LVT3_R_N at (B 2) is labeled only once in the design.
Signal H_CPU1_PROCHOT_G_R_N at (B 3) is labeled only once in the design.
Signal H_CPU0_PROCHOT_G_R_N at (B 3) is labeled only once in the design.
Signal H_CPU_ERR1_GTL_R_N at (B 4) is labeled only once in the design.
Signal FM_CPU_ERR1_LVT3_K_N at (B 2) is labeled only once in the design.
Signal FM_CPU_ERR0_LVT3_K_N at (B 2) is labeled only once in the design.
Signal H_CPU_ERR0_GTL_R_N at (B 4) is labeled only once in the design.
Signal H_CPU_ERR1_GTL_N at (B 3) is labeled only once in the design.
Signal H_CPU_ERR0_GTL_N at (B 3) is labeled only once in the design.
Signal FM_CPU_ERR1_LVT3_R_N at (B 2) is labeled only once in the design.
Signal H_CPU_ERR0_PCH_N at (B 2) is labeled only once in the design.
Signal H_CPU_ERR1_PCH_N at (B 2) is labeled only once in the design.
Signal H_CPU0_PROCHOT_G_PCH_N at (A 3) is labeled only once in the design.

Warnings in Page : @baseboard_fab2_lib.baseboard_fab2(sch_1):Page94
Signal H_CPU0_MEMABC_MEMHOT at (A 4) is labeled only once in the design.
Signal FM_DIMM_EVENT_FET at (B 2) is labeled only once in the design.
Signal H_CPU0_MEMDEF_MEMHOT at (A 4) is labeled only once in the design.
Signal H_CPU1_MEMKLM_MEMHOT at (A 2) is labeled only once in the design.
Signal H_CPU1_MEMGHJ_MEMHOT at (A 2) is labeled only once in the design.

Warnings in Page : @baseboard_fab2_lib.baseboard_fab2(sch_1):Page95
Signal FM_THROTTLE_R_N at (A 2) is labeled only once in the design.
Signal IRQ_CPU1_PROCHOT_G_N at (B 2) is labeled only once in the design.
Signal IRQ_CPU0_PROCHOT_G_N at (B 2) is labeled only once in the design.
Signal  IRQ_CPU0_VRHOT at (B 1) is labeled only once in the design.
Signal  IRQ_CPU1_VRHOT at (B 1) is labeled only once in the design.

Warnings in Page : @baseboard_fab2_lib.baseboard_fab2(sch_1):Page96
Signal PU_GTL2014_2_DIR at (A 4) is labeled only once in the design.
Signal PD_GTL2014_2_VREF at (A 4) is labeled only once in the design.
Signal PU_GTL2014_1_DIR at (B 4) is labeled only once in the design.
Signal PD_GTL2014_1_VREF at (B 4) is labeled only once in the design.

Warnings in Page : @baseboard_fab2_lib.baseboard_fab2(sch_1):Page99
Signal SMB_DDR_GHJ_VPP_SCL_R at (A 2) is labeled only once in the design.
Signal SMB_DDR_GHJ_VPP_SDA_R at (A 2) is labeled only once in the design.
Signal SMB_DDR_KLM_SCL_G at (A 3) is labeled only once in the design.
Signal SMB_DDR_KLM_SDA_G at (A 3) is labeled only once in the design.
Signal TP_SMB_DDR_KLM_EN at (A 3) is labeled only once in the design.
Signal TP_SMB_DDR_GHJ_EN at (A 3) is labeled only once in the design.
Signal SMB_DDR_GHJ_SCL_G at (A 3) is labeled only once in the design.
Signal SMB_DDR_GHJ_SDA_G at (A 3) is labeled only once in the design.
Signal TP_SMB_DDR_DEF_EN at (B 3) is labeled only once in the design.
Signal SMB_DDR_DEF_SCL_G at (B 3) is labeled only once in the design.
Signal SMB_DDR_DEF_SDA_G at (B 3) is labeled only once in the design.
Signal TP_SMB_DDR_ABC_EN at (B 3) is labeled only once in the design.
Signal SMB_DDR_ABC_SCL_G at (B 3) is labeled only once in the design.
Signal SMB_DDR_ABC_SDA_G at (B 3) is labeled only once in the design.
Signal SMB_DDR_ABC_VPP_SCL_R at (B 2) is labeled only once in the design.
Signal SMB_DDR_ABC_VPP_SDA_R at (B 2) is labeled only once in the design.
Signal SMB_DDR_DEF_VPP_SCL_R at (B 2) is labeled only once in the design.
Signal SMB_DDR_KLM_VPP_SDA_R at (A 2) is labeled only once in the design.
Signal SMB_DDR_KLM_VPP_SCL_R at (A 2) is labeled only once in the design.
Signal SMB_DDR_DEF_VPP_SDA_R at (B 2) is labeled only once in the design.

Warnings in Page : @baseboard_fab2_lib.baseboard_fab2(sch_1):Page101
Signal  XTAL_CK_MNG_IN at (A 3) is labeled only once in the design.
Signal XTAL_CK_MNG_OUT_R at (A 3) is labeled only once in the design.
Signal   CLK_25M_BMC_R at (B 2) is labeled only once in the design.
Signal  CLK_25M_CPLD_R at (B 2) is labeled only once in the design.
Signal    A_COMP_CKMNG at (B 2) is labeled only once in the design.
Signal SMB_HOST_STBY_LVC3_SDA_R4 at (A 3) is labeled only once in the design.
Signal SMB_HOST_STBY_LVC3_SCL_R4 at (A 3) is labeled only once in the design.
Signal     TP_CLK_125M at (A 2) is labeled only once in the design.
Signal TP_CLK_125M_BMCA at (A 2) is labeled only once in the design.
Signal TP_CLK5_50M_CKMNG at (B 2) is labeled only once in the design.
Signal CLK_50M_CKMNG_OCP_R at (A 2) is labeled only once in the design.
Signal CLK_50M_CKMNG_BMC_1_R at (B 2) is labeled only once in the design.
Signal PU_33P_33M_SMBADR at (A 3) is labeled only once in the design.
Signal     PD_CKMNG_OE at (A 4) is labeled only once in the design.
Signal CLK_32K_SUSCLK_PLD_R at (B 2) is labeled only once in the design.
Signal CLK_50M_CKMNG_PCH_10GBE_R at (B 2) is labeled only once in the design.
Signal CLK_50M_CKMNG_SPRVLLE_R at (B 2) is labeled only once in the design.
Signal CLK_50M_CKMNG_BMC_2_R at (B 2) is labeled only once in the design.
Signal TP_CLK_96M_CKMNG_N at (A 2) is labeled only once in the design.
Signal TP_CLK_96M_CKMNG_P at (A 2) is labeled only once in the design.
Signal TP_CLK_100M_R_DN at (A 2) is labeled only once in the design.
Signal TP_CLK_100M_R_DP at (A 2) is labeled only once in the design.
Signal XTAL_CK_MNG_OUT at (A 4) is labeled only once in the design.

Warnings in Page : @baseboard_fab2_lib.baseboard_fab2(sch_1):Page102
Signal FM_DB1200_PWRGD_R at (A 3) is labeled only once in the design.
Signal   P3V3_DB1200_R at (B 4) is labeled only once in the design.
Signal   P3V3_DB1200_A at (B 4) is labeled only once in the design.
Signal  P3V3_DB1200_R1 at (B 2) is labeled only once in the design.
Signal SMB_HOST_STBY_LVC3_SDA_R2 at (B 1) has too little display space.

Warnings in Page : @baseboard_fab2_lib.baseboard_fab2(sch_1):Page104
Signal NC_CLK_156M_CPU1_OSC at (B 4) is labeled only once in the design.
Signal NC_CLK_156M_CPU0_OSC at (B 4) is labeled only once in the design.

Warnings in Page : @baseboard_fab2_lib.baseboard_fab2(sch_1):Page108
Signal RST_PCIE_RISER1_PERST_R_N at (B 3) is labeled only once in the design.
Signal TP_SLOTX24_RSVD66 at (B 2) is labeled only once in the design.
Signal TP_SLOTX24_RSVD63 at (B 3) is labeled only once in the design.
Signal     FM_PWRBRK_N at (B 2) has too little display space.

Warnings in Page : @baseboard_fab2_lib.baseboard_fab2(sch_1):Page111
Signal XDP_CPU_TCK_BUF at (A 4) is labeled only once in the design.
Signal    XDP_RSMRST_N at (B 3) is labeled only once in the design.
Signal TP_XDP_OBSDATA_A3 at (B 3) is labeled only once in the design.
Signal TP_XDP_OBSDATA_B0 at (B 3) is labeled only once in the design.
Signal TP_XDP_OBSDATA_B3 at (B 3) is labeled only once in the design.
Signal TP_XDP_CPU_OBSDATA_D3 at (B 2) is labeled only once in the design.
Signal TP_XDP_CPU_OBSDATA_D0 at (B 2) is labeled only once in the design.
Signal TP_XDP_OBSFN_B1 at (B 3) is labeled only once in the design.
Signal TP_XDP_OBSFN_B0 at (B 3) is labeled only once in the design.
Signal TP_XDP_CPU_OBSFN_C0 at (B 2) is labeled only once in the design.
Signal XDP_CPU_GTL_TCK_R2 at (A 4) is labeled only once in the design.
Signal XDP_DEBUG_CONSENT_N at (B 3) is labeled only once in the design.
Signal TP_XDP_OBSDATA_A1 at (B 3) is labeled only once in the design.
Signal TP_XDP_OBSDATA_A0 at (B 3) is labeled only once in the design.
Signal TP_XDP_OBSDATA_B1 at (B 3) is labeled only once in the design.
Signal TP_XDP_CPU_OBSDATA_C3 at (B 2) is labeled only once in the design.
Signal TP_XDP_CPU_OBSDATA_C2 at (B 2) is labeled only once in the design.
Signal TP_XDP_CPU_OBSDATA_C0 at (B 2) is labeled only once in the design.
Signal TP_XDP_CPU_OBSDATA_C1 at (B 2) is labeled only once in the design.
Signal XDP_SPI_PCH_MOSI_BOOT_HALT_N at (B 2) is labeled only once in the design.
Signal TP_XDP_CPU_OBSDATA_D2 at (B 2) is labeled only once in the design.
Signal TP_XDP_CPU_OBSDATA_D1 at (B 2) is labeled only once in the design.
Signal TP_XDP_OBSDATA_B2 at (B 3) is labeled only once in the design.
Signal TP_XDP_OBSDATA_A2 at (B 3) is labeled only once in the design.
Signal FM_DEBUG_RST_BTN_R1_N at (A 1) is labeled only once in the design.

Warnings in Page : @baseboard_fab2_lib.baseboard_fab2(sch_1):Page113
Signal JTAG_MCP_TCK_R1 at (B 1) is labeled only once in the design.
Signal  JTAG_MCP_TCK_R at (B 4) is labeled only once in the design.
Signal  PWRGD_CPU0_G_R at (B 4) is labeled only once in the design.
Signal JTAG_MCP_CPU1_TDI_R at (A 2) is labeled only once in the design.
Signal JTAG_MCP_TMS_R1 at (B 2) is labeled only once in the design.
Signal JTAG_MCP_CPU0_TDI_R at (B 2) is labeled only once in the design.
Signal  JTAG_MCP_TMS_R at (B 4) is labeled only once in the design.
Signal TP_JTAG_MCP_IO8_RSVD at (B 3) is labeled only once in the design.
Signal FM_CPU1_CD_PRES_N at (B 3) has too little display space.

Warnings in Page : @baseboard_fab2_lib.baseboard_fab2(sch_1):Page114
Signal TP_CLK_24M_PMSYNC2 at (A 1) is labeled only once in the design.
Signal   TP_PCH_RSVD64 at (B 4) is labeled only once in the design.
Signal CLK_100M_BMC_PE_DP at (B 3) is labeled only once in the design.
Signal TP_CLK_100M_NSSCC0_DN at (B 4) is labeled only once in the design.
Signal TP_CLK_100M_NSSCC1_DP at (B 4) is labeled only once in the design.
Signal TP_CLK_100M_NSSCC1_DN at (B 4) is labeled only once in the design.
Signal TP_CLK_100M_PLAT1_DN at (B 4) is labeled only once in the design.
Signal TP_CLK_100M_PLAT1_DP at (B 4) is labeled only once in the design.
Signal TP_CLK_100M_NSSCC0_DP at (B 4) is labeled only once in the design.
Signal CLK_100M_BMC_PE_DN at (B 3) is labeled only once in the design.
Signal A_PCH_XCLK_BIASREF at (B 4) is labeled only once in the design.
Signal H_PMSYNC_CLK_24M_R at (A 2) is labeled only once in the design.
Signal   TP_PCH_RSVD65 at (B 4) is labeled only once in the design.

Warnings in Page : @baseboard_fab2_lib.baseboard_fab2(sch_1):Page115
Signal   USB2_P02_DN_R at (A 2) is labeled only once in the design.
Signal  TP_USB2_P03_DN at (A 1) is labeled only once in the design.
Signal  TP_USB2_P03_DP at (A 1) is labeled only once in the design.
Signal  TP_USB2_P06_DP at (B 1) is labeled only once in the design.
Signal USB2_PCH_BMC_P5_DN_R at (A 2) is labeled only once in the design.
Signal   TP_USB2_P8_DP at (B 1) is labeled only once in the design.
Signal   TP_USB2_P9_DN at (B 1) is labeled only once in the design.
Signal     A_USB2_COMP at (B 3) is labeled only once in the design.
Signal TP_USB3_P06_TXN at (B 1) is labeled only once in the design.
Signal TP_USB3_P05_RXN at (B 3) is labeled only once in the design.
Signal     A_USB2_VBUS at (B 3) is labeled only once in the design.
Signal  TP_USB2_P07_DP at (B 1) is labeled only once in the design.
Signal   TP_USB2_P8_DN at (B 1) is labeled only once in the design.
Signal   TP_USB2_P9_DP at (B 1) is labeled only once in the design.
Signal  TP_USB2_P11_DP at (B 1) is labeled only once in the design.
Signal USB_PCH_BMC_P4_DP_R at (A 2) is labeled only once in the design.
Signal USB_PCH_BMC_P4_DN_R at (A 2) is labeled only once in the design.
Signal USB2_PCH_BMC_P5_DP_R at (B 2) is labeled only once in the design.
Signal  TP_USB2_P11_DN at (B 1) is labeled only once in the design.
Signal TP_USB3_P02_RXN at (B 3) is labeled only once in the design.
Signal TP_USB3_P03_RXN at (B 3) is labeled only once in the design.
Signal TP_USB3_P03_RXP at (B 3) is labeled only once in the design.
Signal TP_USB3_P04_RXP at (B 3) is labeled only once in the design.
Signal TP_USB3_P05_RXP at (B 3) is labeled only once in the design.
Signal TP_USB3_P06_RXP at (B 3) is labeled only once in the design.
Signal  TP_USB2_P14_DP at (B 1) is labeled only once in the design.
Signal  TP_USB2_P14_DN at (B 1) is labeled only once in the design.
Signal  TP_USB2_P13_DP at (B 1) is labeled only once in the design.
Signal TP_USB3_P04_RXN at (B 3) is labeled only once in the design.
Signal TP_USB3_P06_RXN at (B 3) is labeled only once in the design.
Signal  TP_USB2_P13_DN at (B 1) is labeled only once in the design.
Signal  TP_USB2_P10_DN at (B 1) is labeled only once in the design.
Signal TP_USB3_P02_TXN at (B 1) is labeled only once in the design.
Signal TP_USB3_P03_TXP at (B 1) is labeled only once in the design.
Signal TP_USB3_P04_TXN at (B 1) is labeled only once in the design.
Signal TP_USB3_P03_TXN at (B 1) is labeled only once in the design.
Signal TP_USB3_P02_TXP at (B 1) is labeled only once in the design.
Signal  TP_USB2_P12_DP at (B 1) is labeled only once in the design.
Signal TP_USB3_P05_TXN at (B 1) is labeled only once in the design.
Signal TP_USB3_P05_TXP at (B 1) is labeled only once in the design.
Signal TP_USB3_P06_TXP at (B 1) is labeled only once in the design.
Signal TP_USB3_P04_TXP at (B 1) is labeled only once in the design.
Signal  TP_USB2_P07_DN at (B 1) is labeled only once in the design.
Signal  TP_USB2_P10_DP at (B 1) is labeled only once in the design.
Signal   TP_PCH_RSVD55 at (B 3) is labeled only once in the design.
Signal   USB2_P02_DP_R at (A 2) is labeled only once in the design.
Signal TP_USB3_P02_RXP at (B 3) is labeled only once in the design.
Signal  TP_USB2_P12_DN at (B 1) is labeled only once in the design.
Signal  TP_USB2_P06_DN at (B 1) is labeled only once in the design.

Warnings in Page : @baseboard_fab2_lib.baseboard_fab2(sch_1):Page116
Signal   TP_PCH_RSVD48 at (A 4) is labeled only once in the design.
Signal       A_EXTCLKN at (A 2) is labeled only once in the design.
Signal   TP_PCH_RSVD51 at (A 1) is labeled only once in the design.
Signal   TP_PCH_RSVD52 at (A 1) is labeled only once in the design.
Signal   TP_PCH_RSVD50 at (A 1) is labeled only once in the design.
Signal   TP_PCH_RSVD47 at (A 4) is labeled only once in the design.
Signal A_PCIEUP_RCOMP_P at (A 4) is labeled only once in the design.
Signal A_PCIEUP_RCOMP_N at (A 4) is labeled only once in the design.
Signal  A_PCIE_RCOMP_P at (A 4) is labeled only once in the design.
Signal       A_EXTCLKP at (A 2) is labeled only once in the design.
Signal  A_PCIE_RCOMP_N at (A 4) is labeled only once in the design.
Signal   TP_PCH_RSVD49 at (A 1) is labeled only once in the design.
Signal P2E_SSB_BMC_TX_DN at (B 2) is labeled only once in the design.
Signal P2E_SSB_BMC_TX_DP at (B 2) is labeled only once in the design.

Warnings in Page : @baseboard_fab2_lib.baseboard_fab2(sch_1):Page118
Signal   TP_PCH_RSVD36 at (B 3) is labeled only once in the design.
Signal   TP_PCH_RSVD35 at (B 3) is labeled only once in the design.
Signal   TP_PCH_RSVD34 at (B 3) is labeled only once in the design.
Signal   TP_PCH_RSVD33 at (B 3) is labeled only once in the design.
Signal   TP_PCH_RSVD32 at (B 3) is labeled only once in the design.
Signal TP_CPU_PCH_TRIGGER_IN at (B 3) is labeled only once in the design.
Signal    TP_SLP_LAN_N at (B 1) is labeled only once in the design.
Signal TP_PLTRST_CPU_N at (B 2) is labeled only once in the design.
Signal     A_KR0_RBIAS at (A 4) is labeled only once in the design.
Signal TP_10GBE_KR1_MON_DP at (A 2) is labeled only once in the design.
Signal     A_KR1_RBIAS at (A 2) is labeled only once in the design.
Signal   TP_PCH_RSVD37 at (A 3) is labeled only once in the design.
Signal   TP_PCH_RSVD38 at (A 3) is labeled only once in the design.
Signal TP_10GBE_KR0_MON_DP at (A 3) is labeled only once in the design.
Signal TP_10GBE_KR0_MON_DN at (A 3) is labeled only once in the design.
Signal TP_CPU_PCH_TRIGGER_OUT at (B 3) is labeled only once in the design.
Signal   TP_PCH_RSVD45 at (B 3) is labeled only once in the design.
Signal RST_BMC_SRST_R_N at (B 3) is labeled only once in the design.
Signal    FM_SLPS3_R_N at (B 3) is labeled only once in the design.
Signal   TP_PCH_RSVD41 at (A 2) is labeled only once in the design.
Signal   TP_PCH_RSVD42 at (A 2) is labeled only once in the design.
Signal TP_10GBE_KR1_MON_DN at (A 2) is labeled only once in the design.
Signal   TP_PCH_RSVD53 at (B 2) is labeled only once in the design.
Signal   TP_PCH_RSVD54 at (B 2) is labeled only once in the design.
Signal  TP_PM_SYNC_GTL at (B 2) is labeled only once in the design.
Signal H_PM_SYNC1_GTL_R at (B 2) is labeled only once in the design.
Signal FM_BATTERY_SENSE_EN_R_N at (B 3) is labeled only once in the design.
Signal TP_PCH_GDP8_SUSCLK at (B 3) is labeled only once in the design.
Signal FM_CPU0_RC_ERROR_R_N at (B 3) is labeled only once in the design.
Signal KR_P1_OCP_TX_DN at (A 2) has too little display space.
Signal KR_P1_OCP_RX_C_DP at (A 3) has too little display space.
Signal FM_GBE_LOM_DISABLE_N at (B 3) has too little display space.

Warnings in Page : @baseboard_fab2_lib.baseboard_fab2(sch_1):Page119
Signal FM_OCP_MEZZA_PRES_R at (B 4) is labeled only once in the design.
Signal FM_BMC_READY_R_N at (B 4) is labeled only once in the design.
Signal CLK_24M_BMC_LPC_R at (B 4) is labeled only once in the design.
Signal FM_THROTTLE_R2_N at (B 2) is labeled only once in the design.
Signal FM_CPU_CATERR_DLY_LVT3_R_N at (B 2) is labeled only once in the design.
Signal    LPC_LAD1_IO1 at (B 4) is labeled only once in the design.
Signal    LPC_LAD0_IO0 at (B 4) is labeled only once in the design.
Signal    LPC_LAD3_IO3 at (B 4) is labeled only once in the design.
Signal    LPC_LAD2_IO2 at (B 4) is labeled only once in the design.
Signal FM_PMBUS_ALERT_BUF_EN_R2_N at (B 4) is labeled only once in the design.
Signal   FM_SLT_CFG2_R at (B 2) is labeled only once in the design.
Signal FM_PMBUS_ALERT_BUF_EN_R_N at (B 2) is labeled only once in the design.
Signal      FM_PWR_LED at (A 3) is labeled only once in the design.
Signal    FM_PWR_LED_K at (A 3) is labeled only once in the design.
Signal    FM_PWR_LED_A at (A 2) is labeled only once in the design.
Signal FM_ADR_MODE_SEL_R at (B 2) is labeled only once in the design.
Signal FM_PCH_PLD_DATA_R at (A 2) is labeled only once in the design.
Signal     FM_SLT_CFG1 at (B 1) has too little display space.
Signal    PU_LPC_PME_N at (B 4) has too little display space.
Signal    RST_PLTRST_N at (B 4) has too little display space.
Signal FM_GLOBAL_RST_WARN_N at (B 4) has too little display space.
Signal RST_SYSTEM_BTN_N at (B 4) has too little display space.
Signal FM_PMBUS_ALERT_BUF_EN_N at (B 4) has too little display space.

Warnings in Page : @baseboard_fab2_lib.baseboard_fab2(sch_1):Page120
Signal IRQ_SML1_PMBUS_ALERT_R1_N at (B 4) is labeled only once in the design.
Signal FM_CPU1_RC_ERROR_R1_N at (B 4) is labeled only once in the design.
Signal FM_POST_CARD_PRES_BMC_R1_N at (B 4) is labeled only once in the design.
Signal FM_BMC_READY_R1_N at (B 4) is labeled only once in the design.
Signal IRQ_DIMM_SAVE_LVT3_R_N at (B 2) is labeled only once in the design.
Signal FM_CPU1_RC_ERROR_R_N at (B 2) is labeled only once in the design.
Signal     A_RCOMP_3P3 at (B 2) is labeled only once in the design.
Signal  TP_PCH_GPP_J23 at (A 1) is labeled only once in the design.
Signal  TP_PCH_GPP_J21 at (A 1) is labeled only once in the design.
Signal  TP_PCH_GPP_J19 at (A 1) is labeled only once in the design.
Signal  TP_PCH_GPP_J17 at (A 1) is labeled only once in the design.
Signal FM_ADR_COMPLETE_R1 at (A 3) is labeled only once in the design.
Signal FM_CPU0_RC_ERROR_R1_N at (B 4) is labeled only once in the design.
Signal FM_CPLD_ADR_TRIGGER_R_N at (B 4) is labeled only once in the design.
Signal SGPIO_PCH_SATA_DOUT0 at (B 4) has too little display space.
Signal LED_PCH_SSATA_HDD_N at (B 4) has too little display space.
Signal JTAG_PCH_PLD_TMS at (B 4) has too little display space.
Signal FM_BIOS_USB_RECOVERY at (B 4) has too little display space.
Signal IRQ_BOARD_BMC_ALERT_N at (B 1) has too little display space.
Signal FM_CPU1_RC_ERROR_N at (B 1) has too little display space.
Signal SGPIO_PCH_SSATA_LOAD at (B 4) has too little display space.
Signal SGPIO_PCH_SSATA_CLOCK at (B 4) has too little display space.
Signal FM_CPU1_RC_ERROR_N at (B 4) has too little display space.

Warnings in Page : @baseboard_fab2_lib.baseboard_fab2(sch_1):Page121
Signal FM_INTRUDER_HDR_PCH_N at (A 4) is labeled only once in the design.
Signal TP_PCH_HDA_SDI_1 at (B 1) is labeled only once in the design.
Signal SPI_PCH_CS0_R_N at (B 2) is labeled only once in the design.
Signal  SPI_PCH_MOSI_R at (B 2) is labeled only once in the design.
Signal TP_PCH_DISPA_SDO at (B 1) is labeled only once in the design.
Signal TP_PCH_DISPA_SDI at (B 1) is labeled only once in the design.
Signal TP_PCH_DISPA_BCLK at (B 1) is labeled only once in the design.
Signal TP_PCH_HDA_SYNC at (B 1) is labeled only once in the design.
Signal TP_PCH_HSA_RST_N at (B 1) is labeled only once in the design.
Signal TP_PCH_HDA_BCLK at (B 1) is labeled only once in the design.
Signal    TP_PCH_RSVD9 at (A 1) is labeled only once in the design.
Signal   TP_PCH_RSVD25 at (A 3) is labeled only once in the design.
Signal  TP_PCH_GPP_L11 at (B 3) is labeled only once in the design.
Signal  TP_PCH_GPP_L10 at (B 3) is labeled only once in the design.
Signal   TP_PCH_RSVD24 at (A 3) is labeled only once in the design.
Signal   TP_PCH_RSVD16 at (A 3) is labeled only once in the design.
Signal   TP_PCH_RSVD14 at (A 3) is labeled only once in the design.
Signal   TP_PCH_RSVD13 at (A 3) is labeled only once in the design.
Signal    TP_PCH_RSVD4 at (A 1) is labeled only once in the design.
Signal   TP_PCH_RSVD15 at (A 3) is labeled only once in the design.
Signal   TP_PCH_RSVD17 at (A 3) is labeled only once in the design.
Signal   TP_PCH_RSVD18 at (A 3) is labeled only once in the design.
Signal   TP_PCH_RSVD19 at (A 3) is labeled only once in the design.
Signal   TP_PCH_RSVD22 at (A 3) is labeled only once in the design.
Signal   TP_PCH_RSVD20 at (A 3) is labeled only once in the design.
Signal   TP_PCH_RSVD21 at (A 3) is labeled only once in the design.
Signal   TP_PCH_RSVD23 at (A 3) is labeled only once in the design.
Signal    TP_PCH_RSVD0 at (A 1) is labeled only once in the design.
Signal    TP_PCH_RSVD1 at (A 1) is labeled only once in the design.
Signal    TP_PCH_RSVD3 at (A 1) is labeled only once in the design.
Signal    TP_PCH_RSVD5 at (A 1) is labeled only once in the design.
Signal    TP_PCH_RSVD6 at (A 1) is labeled only once in the design.
Signal    TP_PCH_RSVD7 at (A 1) is labeled only once in the design.
Signal    TP_PCH_RSVD8 at (A 1) is labeled only once in the design.
Signal TP_PCH_HDA_SDI_0 at (B 1) is labeled only once in the design.
Signal TP_SPI_PCH_CS1_R1_N at (B 1) is labeled only once in the design.
Signal   TP_PCH_RSVD26 at (B 1) is labeled only once in the design.
Signal   TP_PCH_RSVD27 at (B 1) is labeled only once in the design.
Signal   TP_PCH_RSVD46 at (B 1) is labeled only once in the design.
Signal   TP_PCH_RSVD12 at (A 1) is labeled only once in the design.
Signal A_1P8_3P3_RCOMP at (B 4) is labeled only once in the design.
Signal    TP_PCH_RSVD2 at (A 1) is labeled only once in the design.

Warnings in Page : @baseboard_fab2_lib.baseboard_fab2(sch_1):Page122
Signal   TP_PCH_RSVD28 at (A 1) is labeled only once in the design.
Signal   TP_PCH_RSVD29 at (A 1) is labeled only once in the design.
Signal   TP_PCH_RSVD30 at (A 1) is labeled only once in the design.
Signal   TP_PCH_RSVD31 at (A 1) is labeled only once in the design.
Signal   TP_PCH_RSVD58 at (A 1) is labeled only once in the design.
Signal   TP_PCH_RSVD59 at (B 1) is labeled only once in the design.

Warnings in Page : @baseboard_fab2_lib.baseboard_fab2(sch_1):Page134
Signal FM_THERMTRIP_DLY_R at (B 4) is labeled only once in the design.

Warnings in Page : @baseboard_fab2_lib.baseboard_fab2(sch_1):Page135
Signal TP_JUMPER_BLOCK_ 1_7 at (A 3) is labeled only once in the design.
Signal TP_JUMPER_BLOCK_1_1 at (A 3) is labeled only once in the design.
Signal TP_JUMPER_BLOCK_1_2 at (A 1) is labeled only once in the design.
Signal TP_JUMPER_BLOCK_1_8 at (A 1) is labeled only once in the design.
Signal FM_PCH_SATA_RAID_KEY_R at (B 4) is labeled only once in the design.
Signal PU_KEY_CONN_PIN2_R at (B 4) is labeled only once in the design.

Warnings in Page : @baseboard_fab2_lib.baseboard_fab2(sch_1):Page136
Signal PU_BIOS_USB_RECOVERY at (B 2) is labeled only once in the design.
Signal PU_BIOS_RECOVER_BOOT at (B 2) is labeled only once in the design.
Signal TP_BIOS_RECOVER_BOOT at (B 2) is labeled only once in the design.
Signal TP_ME_RCVR_BOOT at (B 3) is labeled only once in the design.
Signal TP_PASSWORD_CLEAR at (B 3) is labeled only once in the design.
Signal    PD_ME_RCVR_N at (B 3) is labeled only once in the design.
Signal PD_PASSWORD_CLEAR at (B 3) is labeled only once in the design.
Signal FM_BIOS_TOP_SWAP_SPKR_R at (A 2) is labeled only once in the design.
Signal RST_PLTRST_TOP_SWAP at (A 2) is labeled only once in the design.
Signal TP_BIOS_USB_RECOVERY at (B 2) is labeled only once in the design.

Warnings in Page : @baseboard_fab2_lib.baseboard_fab2(sch_1):Page137
Signal TP_RST_RTCRST_N at (B 2) is labeled only once in the design.
Signal TP_IE_DEBUG_MODE at (B 4) is labeled only once in the design.
Signal PD_SPI_BMC_BT_CS0_N at (B 3) is labeled only once in the design.
Signal PU_SPI_BMC_BT_CS0_N at (B 3) is labeled only once in the design.
Signal PD_RST_RTCRST_N at (B 3) is labeled only once in the design.
Signal PD_IE_DEBUG_MODE at (B 3) is labeled only once in the design.
Signal  PD_UV_HIGH_SET at (B 4) is labeled only once in the design.
Signal  PU_UV_HIGH_SET at (B 4) is labeled only once in the design.

Warnings in Page : @baseboard_fab2_lib.baseboard_fab2(sch_1):Page139
Signal          A_CTOP at (B 2) is labeled only once in the design.
Signal XTAL_25MHZ_OUT_R at (A 4) is labeled only once in the design.
Signal RMII_BMC_PCH_SPRNGVLLE_CRSDV_R at (B 2) is labeled only once in the design.
Signal RMII_PCH_SPRNGVLLE_ARB_IN_R at (B 2) is labeled only once in the design.
Signal P3V3_STBY_P1V5_LAN_I210 at (B 3) is labeled only once in the design.
Signal PU_JTAG_SPRV_TMS at (B 4) is labeled only once in the design.
Signal PU_JTAG_SPRV_TDI at (B 4) is labeled only once in the design.
Signal PU_JTAG_SPRV_TCK at (B 4) is labeled only once in the design.
Signal    TP_SPRV_SDP0 at (B 2) is labeled only once in the design.
Signal PE_PCH_SPRV_RX_DN at (A 2) is labeled only once in the design.
Signal PE_PCH_SPRV_TX_C_DN at (A 3) is labeled only once in the design.
Signal  SPI_NIC_SCLK_R at (A 2) is labeled only once in the design.
Signal  SPI_NIC_MOSI_R at (A 2) is labeled only once in the design.
Signal          A_CBOT at (B 2) is labeled only once in the design.
Signal   XTAL_25MHZ_IN at (A 4) is labeled only once in the design.
Signal  SPI_NIC_CS_R_N at (A 2) is labeled only once in the design.
Signal PE_PCH_SPRV_RX_DP at (A 2) is labeled only once in the design.
Signal   P1V5_LAN_I210 at (B 3) is labeled only once in the design.
Signal   P0V9_LAN_I210 at (B 3) is labeled only once in the design.
Signal RMII_SPRNGVLLE_BMC_PCH_RXD1_R at (B 2) is labeled only once in the design.
Signal RMII_SPRNGVLLE_BMC_PCH_RXD0_R at (A 2) is labeled only once in the design.
Signal PU_JTAG_SPRV_TDO at (B 2) is labeled only once in the design.
Signal    TP_SPRV_SDP3 at (B 2) is labeled only once in the design.
Signal    TP_SPRV_SDP2 at (B 2) is labeled only once in the design.
Signal PE_PCH_SPRV_TX_C_DP at (A 3) is labeled only once in the design.
Signal    PU_DEV_OFF_N at (B 3) is labeled only once in the design.
Signal PU_SPRV_LAN_PWR_GOOD at (B 4) has too little display space.
Signal RMII_SPRNGVLLE_BMC_PCH_RXD0 at (B 1) has too little display space.

Warnings in Page : @baseboard_fab2_lib.baseboard_fab2(sch_1):Page140
Signal    PU_NV_HOLD_N at (B 2) is labeled only once in the design.
Signal      PU_NV_WP_N at (B 2) is labeled only once in the design.
Signal  SPI_NIC_MISO_R at (B 1) is labeled only once in the design.
Signal    SPI_NIC_CS_N at (B 3) has too little display space.

Warnings in Page : @baseboard_fab2_lib.baseboard_fab2(sch_1):Page141
Signal   LED_LAN_0_R_N at (A 2) is labeled only once in the design.
Signal   LED_LAN_2_R_N at (B 2) is labeled only once in the design.
Signal NIC_LED_ACT_ANODE_R at (A 2) is labeled only once in the design.
Signal   LED_LAN_1_R_N at (A 2) is labeled only once in the design.

Warnings in Page : @baseboard_fab2_lib.baseboard_fab2(sch_1):Page142
Signal PU_TRI_STATE_EN at (B 2) is labeled only once in the design.
Signal IRQ_LVC3_WAKE_R_N at (A 2) is labeled only once in the design.
Signal   FM_ALL_WAKE_N at (B 3) is labeled only once in the design.

Warnings in Page : @baseboard_fab2_lib.baseboard_fab2(sch_1):Page143
Signal    TP_BMC_M_A15 at (B 2) is labeled only once in the design.
Signal        BMC_MIOZ at (B 2) is labeled only once in the design.

Warnings in Page : @baseboard_fab2_lib.baseboard_fab2(sch_1):Page144
Signal SGPIO_BMC_LD_R_N at (B 2) is labeled only once in the design.
Signal FM_CPU1_FIVR_FAULT_LVT3_R_N at (B 2) is labeled only once in the design.
Signal FM_CPU0_FIVR_FAULT_LVT3_R_N at (B 2) is labeled only once in the design.
Signal       A_DACRSET at (A 2) is labeled only once in the design.
Signal SGPIO_BMC_DOUT_R at (B 2) is labeled only once in the design.
Signal SGPIO_BMC_CLK_R at (B 2) is labeled only once in the design.
Signal CLK_48M_USB_BMC_R at (A 4) is labeled only once in the design.

Warnings in Page : @baseboard_fab2_lib.baseboard_fab2(sch_1):Page145
Signal      PECI_BMC_R at (A 3) is labeled only once in the design.
Signal RST_SYSTEM_BTN_R_N at (A 2) is labeled only once in the design.
Signal P2E_SSB_BMC_RX_DP at (A 2) is labeled only once in the design.
Signal       PD_PEREXT at (A 2) is labeled only once in the design.
Signal SMB_DEBUG_STBY_LVC3_SDA_R at (B 3) is labeled only once in the design.
Signal SMB_DEBUG_STBY_LVC3_SCL_R at (B 3) is labeled only once in the design.
Signal SMB_PEHPCPU0_STBY_LVC3_R2_SCL at (B 3) is labeled only once in the design.
Signal SMB_PEHPCPU0_STBY_LVC3_R2_SDA at (B 3) is labeled only once in the design.
Signal   PU_24M_OSC_OE at (B 4) is labeled only once in the design.
Signal CLK_24M_BMC_CLKIN_R at (B 3) is labeled only once in the design.
Signal FM_PMBUS_ALERT_BUF_EN_R3_N at (B 2) is labeled only once in the design.
Signal FM_PWR_BTN_R1_N at (A 2) is labeled only once in the design.
Signal RST_PLTRST_BUF_N_R at (A 3) is labeled only once in the design.
Signal P2E_SSB_BMC_RX_DN at (A 2) is labeled only once in the design.
Signal   TP_BMC_GPIOA2 at (A 3) is labeled only once in the design.
Signal FM_BMC_SYS_THROTTLE_R_N at (A 3) is labeled only once in the design.
Signal FM_BOARD_REV_ID2 at (B 4) has too little display space.
Signal FM_OCP_MEZZC_PRES_LVT3_BMC at (B 1) has too little display space.
Signal IRQ_DIMM_SAVE_LVT3_N at (B 4) has too little display space.

Warnings in Page : @baseboard_fab2_lib.baseboard_fab2(sch_1):Page146
Signal  FM_BMC_NMI_N_R at (B 4) is labeled only once in the design.
Signal IRQ_LPC_SERIRQ_R at (A 4) is labeled only once in the design.
Signal  RST_BMC_LVC3_N at (A 4) is labeled only once in the design.
Signal SPI_BMC_BT_CLK_R at (A 4) is labeled only once in the design.
Signal SPI_BMC_BT_DO_R at (B 4) is labeled only once in the design.
Signal    PD_SP_ENTEST at (B 4) is labeled only once in the design.
Signal SPI_BMC_BT_CS_R_N at (A 2) is labeled only once in the design.
Signal RST_BMC_PLTRST_BUF_N at (A 2) is labeled only once in the design.
Signal     A_USB2AVRES at (B 2) is labeled only once in the design.
Signal     A_USB2BVRES at (B 2) is labeled only once in the design.
Signal  LPC_LAD2_IO2_R at (A 4) is labeled only once in the design.
Signal  LPC_LAD3_IO3_R at (A 4) is labeled only once in the design.
Signal LPC_LFRAME_N_CS0_R_N at (A 4) is labeled only once in the design.
Signal  LPC_LAD1_IO1_R at (A 4) is labeled only once in the design.
Signal  LPC_LAD0_IO0_R at (A 4) is labeled only once in the design.
Signal CLK_24M_BMC_LPC at (A 4) has too little display space.

Warnings in Page : @baseboard_fab2_lib.baseboard_fab2(sch_1):Page147
Signal FM_GLOBAL_RST_WARN_N_R at (B 2) is labeled only once in the design.
Signal  BMC_RSMRST_B_N at (B 4) is labeled only once in the design.
Signal RMII_BMC_OCP_TXEN_R at (B 2) is labeled only once in the design.
Signal RMII_BMC_SPRNGVLLE_TXEN_R at (B 2) is labeled only once in the design.
Signal P3V3_STBY_BMC_ADCVREFN at (A 2) is labeled only once in the design.
Signal      PD_ADCREXT at (A 2) is labeled only once in the design.
Signal P3V3_STBY_BMC_ADCVREFP at (A 2) is labeled only once in the design.

Warnings in Page : @baseboard_fab2_lib.baseboard_fab2(sch_1):Page148
Signal     VCCBAT_TW12 at (B 3) is labeled only once in the design.
Signal   PVCCIO_CPU0_R at (A 3) is labeled only once in the design.

Warnings in Page : @baseboard_fab2_lib.baseboard_fab2(sch_1):Page151
Signal RST_BMC_DDR3_R_N at (B 2) is labeled only once in the design.
Signal       BMC_M_CLK at (A 2) is labeled only once in the design.
Signal          BMC_ZQ at (B 2) is labeled only once in the design.
Signal FM_HEARTBEAT_LED_K at (B 3) is labeled only once in the design.
Signal FM_HEARTBEAT_LED at (A 4) is labeled only once in the design.
Signal FM_HEARTBEAT_LED_A at (B 3) is labeled only once in the design.
Signal      BMC_M_DQ13 at (A 2) has too little display space.

Warnings in Page : @baseboard_fab2_lib.baseboard_fab2(sch_1):Page152
Signal H_CPU0_MEMABC_MEMHOT_G_PCH_N at (B 3) is labeled only once in the design.
Signal H_CPU0_MEMABC_MEMHOT_LVT3_K_N at (B 2) is labeled only once in the design.
Signal H_CPU0_MEMDEF_MEMHOT_LVT3_K_N at (B 2) is labeled only once in the design.
Signal H_CPU1_MEMKLM_MEMHOT_LVT3_K_N at (B 2) is labeled only once in the design.
Signal H_CPU1_MEMGHJ_MEMHOT_LVT3_K_N at (B 2) is labeled only once in the design.
Signal H_CPU1_KLM_MEMHOT_LVT3_R_N at (B 2) is labeled only once in the design.
Signal H_CPU1_GHJ_MEMHOT_LVT3_R_N at (B 2) is labeled only once in the design.
Signal H_CPU1_MEMKLM_MEMHOT_G_PCH_N at (B 3) is labeled only once in the design.
Signal H_CPU1_MEMGHJ_MEMHOT_G_PCH_N at (B 3) is labeled only once in the design.
Signal        PD_DIR_2 at (B 2) is labeled only once in the design.
Signal H_CPU0_MEMDEF_MEMHOT_G_PCH_N at (B 3) is labeled only once in the design.
Signal H_CPU0_ABC_MEMHOT_LVT3_R_N at (B 2) is labeled only once in the design.
Signal H_CPU0_MEMABC_MEMHOT_G_R_N at (B 3) is labeled only once in the design.
Signal H_CPU1_MEMGHJ_MEMHOT_G_R_N at (B 3) is labeled only once in the design.
Signal H_CPU1_MEMKLM_MEMHOT_G_R_N at (B 3) is labeled only once in the design.
Signal H_CPU0_DEF_MEMHOT_LVT3_R_N at (B 2) is labeled only once in the design.
Signal H_CPU0_MEMDEF_MEMHOT_G_R_N at (B 3) is labeled only once in the design.

Warnings in Page : @baseboard_fab2_lib.baseboard_fab2(sch_1):Page153
Signal      SPI_CLK_R1 at (A 3) is labeled only once in the design.
Signal     PU_SPI1_RST at (A 3) is labeled only once in the design.
Signal     SPI_MISO_R0 at (B 3) is labeled only once in the design.
Signal      TP_SPI_0_3 at (B 2) is labeled only once in the design.
Signal      TP_SPI_0_4 at (B 2) is labeled only once in the design.
Signal      TP_SPI_0_5 at (B 2) is labeled only once in the design.
Signal      TP_SPI_0_6 at (B 2) is labeled only once in the design.
Signal     PU_SPI0_RST at (B 3) is labeled only once in the design.
Signal      TP_SPI_1_1 at (A 2) is labeled only once in the design.
Signal      TP_SPI_1_0 at (A 2) is labeled only once in the design.
Signal      TP_SPI_1_2 at (A 2) is labeled only once in the design.
Signal      TP_SPI_1_3 at (A 2) is labeled only once in the design.
Signal      TP_SPI_1_5 at (A 2) is labeled only once in the design.
Signal     SPI_MISO_R1 at (A 3) is labeled only once in the design.
Signal SPI_SWITCH_MOSI_R1 at (A 4) is labeled only once in the design.
Signal      TP_SPI_1_4 at (A 2) is labeled only once in the design.
Signal      TP_SPI_1_6 at (A 2) is labeled only once in the design.
Signal      TP_SPI_0_0 at (B 2) is labeled only once in the design.
Signal      TP_SPI_0_1 at (B 2) is labeled only once in the design.
Signal      TP_SPI_0_2 at (B 2) is labeled only once in the design.
Signal SPI_SWITCH_MOSI_R0 at (B 3) is labeled only once in the design.
Signal      SPI_CLK_R0 at (B 3) is labeled only once in the design.

Warnings in Page : @baseboard_fab2_lib.baseboard_fab2(sch_1):Page154
Signal FM_DUAL_BIOS_SEL_N at (A 2) is labeled only once in the design.
Signal TP_SPI_SWITCH1_12 at (B 1) is labeled only once in the design.
Signal  SPI_PCH_MISO_R at (B 4) is labeled only once in the design.
Signal TP_SPI_SWITCH1_9 at (B 1) is labeled only once in the design.
Signal TP_SPI_SWITCH1_14 at (B 2) is labeled only once in the design.
Signal TP_SPI_SWITCH1_13 at (B 2) is labeled only once in the design.
Signal TP_SPI_SWITCH1_10 at (B 2) is labeled only once in the design.
Signal TP_SPI_SWITCH1_3 at (B 2) is labeled only once in the design.
Signal TP_SPI_SWITCH1_6 at (B 2) is labeled only once in the design.
Signal TP_SPI_SWITCH1_11 at (B 2) is labeled only once in the design.
Signal  SPI_PCH_IO2_R1 at (B 2) is labeled only once in the design.
Signal  SPI_PCH_IO3_R1 at (B 2) is labeled only once in the design.
Signal SPI_CS0_PRIMARY_N at (A 2) is labeled only once in the design.
Signal SPI_CS0_SECONDARY_N at (A 2) is labeled only once in the design.

Warnings in Page : @baseboard_fab2_lib.baseboard_fab2(sch_1):Page155
Signal FM_CPLD_DBG_PWR_EN at (A 3) is labeled only once in the design.
Signal FM_CPLD_DBG_PWR_EN_R_N at (A 4) is labeled only once in the design.
Signal    P5V_STBY_DBG at (B 3) is labeled only once in the design.
Signal P5V_STBY_DGB_FS at (A 3) is labeled only once in the design.
Signal   SPA_5V_SIN_SW at (A 3) is labeled only once in the design.
Signal SPA_5V_SIN_SW_D at (A 2) is labeled only once in the design.
Signal    SPA_SIN_SW_R at (A 1) is labeled only once in the design.

Warnings in Page : @baseboard_fab2_lib.baseboard_fab2(sch_1):Page156
Signal RST_BMC_SYSRST_BTN_OUT_B_R_N at (B 2) is labeled only once in the design.
Signal FM_PCH_PWRBTN_R_N at (B 2) is labeled only once in the design.

Warnings in Page : @baseboard_fab2_lib.baseboard_fab2(sch_1):Page157
Signal FP_NMI_BTN_OUT_N at (B 2) is labeled only once in the design.
Signal  FP_NMI_BTN_R_N at (B 1) is labeled only once in the design.
Signal FP_NMI_BTN_OUT_R_N at (B 3) is labeled only once in the design.
Signal      FP_NMI_BTN at (A 2) is labeled only once in the design.
Signal H_CPU0_FAST_WAKE at (A 4) is labeled only once in the design.
Signal H_CPU0_FAST_WAKE_B_N at (A 4) is labeled only once in the design.
Signal RST_BMC_SRST_R2_N at (A 2) is labeled only once in the design.

Warnings in Page : @baseboard_fab2_lib.baseboard_fab2(sch_1):Page158
Signal SP2_BMC_CM_UART_TX_R at (B 2) is labeled only once in the design.
Signal  UART_MUX_OUT_R at (B 1) is labeled only once in the design.
Signal FM_UARTSW_MSB_R_N at (B 3) is labeled only once in the design.
Signal FM_UARTSW_LSB_R_N at (B 3) is labeled only once in the design.
Signal   UART_MUX_IN_R at (A 2) is labeled only once in the design.
Signal SP2_BMC_CM_UART_RX_R at (A 2) is labeled only once in the design.
Signal   UART_BMC_RXD5 at (A 1) has too little display space.
Signal SP2_BMC_CM_UART_RX at (A 1) has too little display space.
Signal SP1_BMC_HOST_UART_RX at (A 1) has too little display space.

Warnings in Page : @baseboard_fab2_lib.baseboard_fab2(sch_1):Page161
Signal FAN_TACH2_CPU1_D1 at (A 1) is labeled only once in the design.
Signal FAN_TACH0_CPU0_D2 at (B 2) is labeled only once in the design.
Signal FAN_TACH0_CPU0_D1 at (B 1) is labeled only once in the design.
Signal FAN_TACH2_CPU1_D2 at (A 2) is labeled only once in the design.
Signal FAN_PWM_OUT_SYS1_BUF at (A 4) is labeled only once in the design.
Signal FAN_PWM_OUT_SYS0_BUF at (B 4) is labeled only once in the design.

Warnings in Page : @baseboard_fab2_lib.baseboard_fab2(sch_1):Page162
Signal PU_SPI_BMC_BT_WP_N at (A 3) is labeled only once in the design.
Signal SPI_BMC_BT_DI_R at (A 3) is labeled only once in the design.
Signal PU_SPI_BMC_BT_HOLD_N at (A 3) is labeled only once in the design.
Signal      TP_SPI_2_1 at (A 2) is labeled only once in the design.
Signal PU_SPI_FLASH_RESET_2_N at (B 3) is labeled only once in the design.
Signal      TP_SPI_2_5 at (B 2) is labeled only once in the design.
Signal      TP_SPI_2_3 at (A 2) is labeled only once in the design.
Signal      TP_SPI_2_2 at (A 2) is labeled only once in the design.
Signal      TP_SPI_2_4 at (A 2) is labeled only once in the design.
Signal      TP_SPI_2_6 at (B 2) is labeled only once in the design.
Signal      TP_SPI_2_0 at (A 2) is labeled only once in the design.

Warnings in Page : @baseboard_fab2_lib.baseboard_fab2(sch_1):Page163
Signal SMB_CPU1_PE_HP_GTL_R_SCL at (B 3) is labeled only once in the design.
Signal SMB_CPU1_PE_HP_GTL_R_SDA at (B 3) is labeled only once in the design.
Signal SMB_PEHPCPU1_STBY_LVC3_R_SCL at (B 2) is labeled only once in the design.
Signal TP_SMB_PEHPCPU1_EN at (B 2) is labeled only once in the design.
Signal SMB_PEHPCPU1_STBY_LVC3_R_SDA at (B 2) is labeled only once in the design.

Warnings in Page : @baseboard_fab2_lib.baseboard_fab2(sch_1):Page164
Signal   PCA9554_INT_N at (B 1) is labeled only once in the design.

Warnings in Page : @baseboard_fab2_lib.baseboard_fab2(sch_1):Page167
Signal ISENSE_TMP421_1_E at (B 3) is labeled only once in the design.
Signal ISENSE_TMP421_1_DXP at (B 3) is labeled only once in the design.
Signal  PD_TMP421_1_A0 at (B 3) is labeled only once in the design.
Signal  PU_TMP421_1_A1 at (B 3) is labeled only once in the design.
Signal ISENSE_TMP421_1_DXN at (B 3) is labeled only once in the design.
Signal ISENSE_TMP421_2_E at (B 3) is labeled only once in the design.
Signal ISENSE_TMP421_2_BC at (B 3) is labeled only once in the design.
Signal       PD_FRU_WP at (A 2) is labeled only once in the design.
Signal  PU_TMP421_2_A0 at (B 2) is labeled only once in the design.
Signal SMB_SENSOR_TMP421_2_SDA at (B 2) is labeled only once in the design.
Signal SMB_SENSOR_TMP421_2_SCL at (B 2) is labeled only once in the design.
Signal SMB_SENSOR_STBY_LVC3_SDA_R2 at (A 2) is labeled only once in the design.
Signal  PD_TMP421_2_A1 at (B 2) is labeled only once in the design.
Signal ISENSE_TMP421_2_DXN at (B 2) is labeled only once in the design.
Signal SMB_SENSOR_STBY_LVC3_SCL_R2 at (A 2) is labeled only once in the design.
Signal   PU_AT24C64_A2 at (A 2) is labeled only once in the design.
Signal SMB_SENSOR_TMP421_1_SCL at (B 2) is labeled only once in the design.
Signal SMB_SENSOR_TMP421_1_SDA at (B 2) is labeled only once in the design.
Signal ISENSE_TMP421_2_DXP at (B 3) is labeled only once in the design.
Signal ISENSE_TMP421_1_BC at (B 3) is labeled only once in the design.

Warnings in Page : @baseboard_fab2_lib.baseboard_fab2(sch_1):Page168
Signal   FM_UART_SEL_N at (A 3) is labeled only once in the design.
Signal FM_DB_UART_SEL3_N at (B 3) is labeled only once in the design.
Signal FM_DB_UART_SEL0_N at (B 4) is labeled only once in the design.
Signal   FM_DB_PRESENT at (B 2) is labeled only once in the design.
Signal    TP_FET_Q56_4 at (B 1) is labeled only once in the design.
Signal    TP_FET_Q56_3 at (B 1) is labeled only once in the design.
Signal FM_DB_UART_SEL2_N at (B 3) is labeled only once in the design.
Signal FM_DB_UART_SEL1_N at (B 4) is labeled only once in the design.
Signal FM_DB_UART_SEL4_N at (B 3) is labeled only once in the design.

Warnings in Page : @baseboard_fab2_lib.baseboard_fab2(sch_1):Page169
Signal P3V_BAT_SOURCE_R at (B 2) is labeled only once in the design.
Signal FM_BATTERY_SENSE_EN at (B 2) is labeled only once in the design.

Warnings in Page : @baseboard_fab2_lib.baseboard_fab2(sch_1):Page170
Signal FM_FAST_PROCHOT_EN at (A 3) is labeled only once in the design.
Signal FM_PMBUS_ALERT_BUF_EN at (B 4) is labeled only once in the design.
Signal FM_FAST_PROCHOT_THROTTLE_DLY_BUF_N at (A 3) is labeled only once in the design.
Signal FM_THROTTLE_R1_N at (A 2) is labeled only once in the design.
Signal IRQ_SML1_PMBUS_ALERT_BUF_N at (B 3) is labeled only once in the design.
Signal IRQ_FORCE_NM_THROTTLE_R_N at (B 3) is labeled only once in the design.
Signal FM_FAST_PROCHOT_AND_OUT_0_N at (B 2) is labeled only once in the design.
Signal FM_FAST_PROCHOT_AND_OUT_1_N at (B 2) is labeled only once in the design.

Warnings in Page : @baseboard_fab2_lib.baseboard_fab2(sch_1):Page172
Signal    P5V_HDD_SATA at (B 2) is labeled only once in the design.
Signal SATA6G_S1_TX_C_DN at (B 3) is labeled only once in the design.
Signal SATA6G_S1_TX_C_DP at (B 3) is labeled only once in the design.
Signal   P12V_HDD_SATA at (B 2) is labeled only once in the design.
Signal SATA6G_S1_RX_C_DP at (B 3) is labeled only once in the design.
Signal SATA6G_S1_RX_C_DN at (B 3) is labeled only once in the design.

Warnings in Page : @baseboard_fab2_lib.baseboard_fab2(sch_1):Page173
Signal SATA6G_P1_TX_C_DP at (B 2) is labeled only once in the design.
Signal SATA6G_P2_RX_C_DN at (B 3) is labeled only once in the design.
Signal SATA6G_P3_RX_C_DN at (B 3) is labeled only once in the design.
Signal SATA6G_P7_TX_C_DN at (A 2) is labeled only once in the design.
Signal SATA6G_P0_TX_C_DN at (B 2) is labeled only once in the design.
Signal PD_SATA0_CONTROLLER_TYPE_R at (B 2) is labeled only once in the design.
Signal SATA6G_P2_TX_C_DP at (B 2) is labeled only once in the design.
Signal SATA6G_P6_RX_C_DP at (A 3) is labeled only once in the design.
Signal SATA6G_P6_RX_C_DN at (A 3) is labeled only once in the design.
Signal SATA6G_P7_RX_C_DN at (A 3) is labeled only once in the design.
Signal SATA6G_P7_RX_C_DP at (A 3) is labeled only once in the design.
Signal SATA6G_P7_TX_C_DP at (A 2) is labeled only once in the design.
Signal SATA6G_P1_TX_C_DN at (B 2) is labeled only once in the design.
Signal SATA6G_P0_TX_C_DP at (B 2) is labeled only once in the design.
Signal SATA6G_P5_TX_C_DP at (A 2) is labeled only once in the design.
Signal SATA6G_P5_TX_C_DN at (A 2) is labeled only once in the design.
Signal SATA6G_P6_TX_C_DN at (A 2) is labeled only once in the design.
Signal SATA6G_P3_TX_C_DN at (B 2) is labeled only once in the design.
Signal SATA6G_P3_TX_C_DP at (B 2) is labeled only once in the design.
Signal PD_SATA1_CONTROLLER_TYPE_R at (A 2) is labeled only once in the design.
Signal SATA6G_P4_RX_C_DN at (A 3) is labeled only once in the design.
Signal SATA6G_P3_RX_C_DP at (B 3) is labeled only once in the design.
Signal SATA6G_P2_RX_C_DP at (B 3) is labeled only once in the design.
Signal SATA6G_P1_RX_C_DN at (B 3) is labeled only once in the design.
Signal SATA6G_P4_RX_C_DP at (A 3) is labeled only once in the design.
Signal SATA6G_P5_RX_C_DP at (A 3) is labeled only once in the design.
Signal SATA6G_P5_RX_C_DN at (A 3) is labeled only once in the design.
Signal PU_DATAIN1_SATA_1_R at (A 3) is labeled only once in the design.
Signal TP_FM_QAT_CBL_PRSNT1_N_R at (A 3) is labeled only once in the design.
Signal TP_SGPIO_SATA_DATA1_R at (A 3) is labeled only once in the design.
Signal TP_SGPIO_SATA_CLOCK1_R at (A 2) is labeled only once in the design.
Signal TP_SGPIO_SATA_LOAD1_R at (A 2) is labeled only once in the design.
Signal SATA6G_P4_TX_C_DN at (A 2) is labeled only once in the design.
Signal SATA6G_P0_RX_C_DN at (B 3) is labeled only once in the design.
Signal SATA6G_P0_RX_C_DP at (B 3) is labeled only once in the design.
Signal SATA6G_P4_TX_C_DP at (A 2) is labeled only once in the design.
Signal SATA6G_P2_TX_C_DN at (B 2) is labeled only once in the design.
Signal TP_FM_QAT_CBL_PRSNT0_R_N at (B 3) is labeled only once in the design.
Signal SATA6G_P1_RX_C_DP at (B 3) is labeled only once in the design.
Signal PU_DATAIN1_SATA_0_R at (B 3) is labeled only once in the design.
Signal SATA6G_P6_TX_C_DP at (A 2) is labeled only once in the design.

Warnings in Page : @baseboard_fab2_lib.baseboard_fab2(sch_1):Page175
Signal FM_SPEAKER_PCH_N at (A 3) is labeled only once in the design.
Signal   FM_BEEP_LED_P at (A 3) is labeled only once in the design.
Signal  FP_RST_BTN_R_N at (B 3) is labeled only once in the design.
Signal FP_PWR_BTN_R1_N at (B 3) is labeled only once in the design.
Signal    PWRGD_P3V3_R at (A 2) is labeled only once in the design.
Signal FP_PWR_BTN_BUF1_N at (B 2) is labeled only once in the design.
Signal  FM_PWR_BTN_R_N at (B 2) is labeled only once in the design.
Signal FP_ID_LED_P5V_STBY_N at (A 2) is labeled only once in the design.
Signal FP_ID_LED_XOR_R at (A 1) is labeled only once in the design.
Signal FP_RST_BTN_BUF1_N at (A 2) is labeled only once in the design.

Warnings in Page : @baseboard_fab2_lib.baseboard_fab2(sch_1):Page176
Signal SPA_MID_DBG1_TX_EN at (A 2) is labeled only once in the design.
Signal FM_USB_P0_EN_R_N at (A 3) is labeled only once in the design.
Signal     P5V_TPS2061 at (B 3) is labeled only once in the design.
Signal TP_USB_ESD_OUT3 at (B 2) is labeled only once in the design.
Signal TP_USB_ESD_OUT2 at (B 2) is labeled only once in the design.
Signal SPA_MID_DBG2_TX_R at (A 2) is labeled only once in the design.
Signal SPA_MID_DBG1_TX_R at (A 2) is labeled only once in the design.
Signal  TP_USB_ESD_AC2 at (B 3) is labeled only once in the design.
Signal  TP_USB_ESD_AC3 at (B 3) is labeled only once in the design.
Signal USB2_P01_ESD_DN at (B 3) is labeled only once in the design.
Signal USB2_P01_ESD_DP at (B 3) is labeled only once in the design.
Signal SPA_MID_DBG2_RX_BUF at (A 2) is labeled only once in the design.

Warnings in Page : @baseboard_fab2_lib.baseboard_fab2(sch_1):Page177
Signal LED_SATA_ACT_R_N at (A 3) is labeled only once in the design.
Signal LED_SAS_ACT_R_N at (A 3) is labeled only once in the design.
Signal FP_LED_HDD_ACTIVITY_AND_R_N at (A 2) is labeled only once in the design.
Signal FM_BMC_FAULT_LED at (B 3) is labeled only once in the design.
Signal FM_RED_LED_CATHODE at (B 3) is labeled only once in the design.
Signal FM_RED_LED_ANODE at (B 3) is labeled only once in the design.
Signal    LED_P5V_STBY at (B 1) is labeled only once in the design.
Signal FP_LED_HDD_ACTIVITY_AND_N at (A 3) is labeled only once in the design.

Warnings in Page : @baseboard_fab2_lib.baseboard_fab2(sch_1):Page178
Signal SGPIO_PCH_SSATA_LOAD_R at (A 2) is labeled only once in the design.
Signal SGPIO_PCH_SSATA_CLOCK_R at (A 2) is labeled only once in the design.
Signal SGPIO_PCH_SSATA_DOUT0_R at (A 2) is labeled only once in the design.

Warnings in Page : @baseboard_fab2_lib.baseboard_fab2(sch_1):Page181
Signal FM_MATED_IN_D1_N at (A 3) is labeled only once in the design.
Signal SPA_MID_DBG_RX_R at (B 3) is labeled only once in the design.
Signal SPA_MID_DBG_TX_R at (B 3) is labeled only once in the design.
Signal FM_CTNR_PS_ON_R at (A 2) is labeled only once in the design.
Signal P3E_CPU1_PE3_MP_C_TXN<1> at (B 2) is labeled only once in the design.
Signal P3E_CPU1_PE3_MP_C_TXN<4> at (B 2) is labeled only once in the design.
Signal P3E_CPU1_PE3_MP_C_TXP<6> at (B 2) is labeled only once in the design.
Signal P3E_CPU1_PE3_MP_C_TXP<0> at (B 2) is labeled only once in the design.
Signal P3E_CPU1_PE3_MP_C_TXN<7> at (B 2) is labeled only once in the design.
Signal P3E_CPU1_PE3_MP_C_TXP<5> at (B 2) is labeled only once in the design.
Signal P3E_CPU1_PE3_MP_C_TXN<0> at (B 2) is labeled only once in the design.
Signal P3E_CPU1_PE3_MP_C_TXP<1> at (B 2) is labeled only once in the design.
Signal P3E_CPU1_PE3_MP_C_TXP<3> at (B 2) is labeled only once in the design.
Signal P3E_CPU1_PE3_MP_C_TXN<3> at (B 2) is labeled only once in the design.
Signal P3E_CPU1_PE3_MP_C_TXP<7> at (B 2) is labeled only once in the design.
Signal P3E_CPU1_PE3_MP_C_TXN<6> at (B 2) is labeled only once in the design.
Signal P3E_CPU1_PE3_MP_C_TXP<4> at (B 2) is labeled only once in the design.
Signal P3E_CPU1_PE3_MP_C_TXN<5> at (B 2) is labeled only once in the design.
Signal P3E_CPU1_PE3_MP_C_TXN<2> at (B 2) is labeled only once in the design.
Signal P3E_CPU1_PE3_MP_C_TXP<2> at (B 2) is labeled only once in the design.
Signal FM_MATED_IN_D2_N at (A 3) is labeled only once in the design.

Warnings in Page : @baseboard_fab2_lib.baseboard_fab2(sch_1):Page182
Signal P3E_CPU1_PE3_MP_C_TXP<10> at (A 2) is labeled only once in the design.
Signal         TP_IOA5 at (B 2) is labeled only once in the design.
Signal P3E_CPU1_PE3_MP_C_TXP<11> at (B 2) is labeled only once in the design.
Signal P3E_CPU1_PE3_MP_C_TXP<12> at (A 2) is labeled only once in the design.
Signal P3E_CPU1_PE3_MP_C_TXP<9> at (A 2) is labeled only once in the design.
Signal P3E_CPU1_PE3_MP_C_TXN<10> at (A 2) is labeled only once in the design.
Signal         TP_IOF4 at (A 4) is labeled only once in the design.
Signal         TP_IOE4 at (A 4) is labeled only once in the design.
Signal         TP_IOH4 at (A 4) is labeled only once in the design.
Signal    TP_FM_WAKE_N at (A 4) is labeled only once in the design.
Signal         TP_IOH3 at (A 4) is labeled only once in the design.
Signal         TP_IOG3 at (A 4) is labeled only once in the design.
Signal         TP_IOI4 at (A 4) is labeled only once in the design.
Signal P3E_CPU1_PE3_MP_C_TXN<14> at (B 2) is labeled only once in the design.
Signal P3E_CPU1_PE3_MP_C_TXN<12> at (A 2) is labeled only once in the design.
Signal P3E_CPU1_PE3_MP_C_TXN<13> at (A 2) is labeled only once in the design.
Signal P3E_CPU1_PE3_MP_C_TXP<13> at (A 2) is labeled only once in the design.
Signal P3E_CPU1_PE3_MP_C_TXN<8> at (A 2) is labeled only once in the design.
Signal P3E_CPU1_PE3_MP_C_TXP<8> at (A 2) is labeled only once in the design.
Signal P3E_CPU1_PE3_MP_C_TXN<9> at (A 2) is labeled only once in the design.
Signal P3E_CPU1_PE3_MP_C_TXP<14> at (B 2) is labeled only once in the design.
Signal P3E_CPU1_PE3_MP_C_TXN<15> at (B 2) is labeled only once in the design.
Signal P3E_CPU1_PE3_MP_C_TXP<15> at (B 2) is labeled only once in the design.
Signal P3E_CPU1_PE3_MP_C_TXN<11> at (B 2) is labeled only once in the design.

Warnings in Page : @baseboard_fab2_lib.baseboard_fab2(sch_1):Page184
Signal SPI_PCH_TPM_CS_R_N at (A 3) is labeled only once in the design.
Signal SPI_PCH_TPM_MOSI_R at (B 3) is labeled only once in the design.
Signal IRQ_SPI_TPM_N_R at (A 2) is labeled only once in the design.
Signal SPI_PCH_TPM_MISO_R at (A 3) is labeled only once in the design.
Signal SPI_PCH_TPM_CLK_R at (B 3) is labeled only once in the design.

Warnings in Page : @baseboard_fab2_lib.baseboard_fab2(sch_1):Page185
Signal P3E_PCH_M2_TX_C_DP<2> at (B 3) is labeled only once in the design.
Signal VREF_LMV431_1V42 at (A 4) is labeled only once in the design.
Signal  FM_M2_DET_LVC3 at (B 3) is labeled only once in the design.
Signal    TP_M2_DEVSLP at (B 4) is labeled only once in the design.
Signal P3E_PCH_M2_TX_C_DP<1> at (B 3) is labeled only once in the design.
Signal P3E_PCH_M2_TX_C_DN<1> at (B 3) is labeled only once in the design.
Signal FM_M2_SSD_PEDET at (B 3) is labeled only once in the design.
Signal P3E_PCH_M2_TX_C_DN<2> at (B 3) is labeled only once in the design.
Signal P3E_PCH_M2_TX_C_DP<3> at (B 3) is labeled only once in the design.
Signal    SMB_M2_SDA_R at (B 2) is labeled only once in the design.
Signal TP_M2_32M_SUSCLK at (B 4) is labeled only once in the design.
Signal PU_M2_CLK_REQ_N at (B 4) is labeled only once in the design.
Signal TP_LED_M2_ACT_N at (B 4) is labeled only once in the design.
Signal        NC_M2<1> at (B 4) is labeled only once in the design.
Signal        NC_M2<0> at (B 4) is labeled only once in the design.
Signal    SMB_M2_SCL_R at (B 2) is labeled only once in the design.
Signal    PD_SMB_M2_EN at (B 1) is labeled only once in the design.
Signal  SMB_M2_ALT_R_N at (B 2) is labeled only once in the design.
Signal P3E_PCH_M2_TX_C_DN<3> at (B 3) is labeled only once in the design.

Warnings in Page : @baseboard_fab2_lib.baseboard_fab2(sch_1):Page186
Signal FM_MEZZA_PRSNT1_N at (B 3) is labeled only once in the design.
Signal RMII_BMC_OCP_RXD1_R at (B 3) is labeled only once in the design.
Signal RMII_BMC_OCP_RXD0_R at (B 3) is labeled only once in the design.
Signal RST_PCIE_CPU_DEV0_R_N at (B 3) is labeled only once in the design.
Signal RMII_BMC_OCP_RXER_R at (B 2) is labeled only once in the design.
Signal RMII_BMC_OCP_CRSDV_R at (B 3) is labeled only once in the design.

Warnings in Page : @baseboard_fab2_lib.baseboard_fab2(sch_1):Page187
Signal RST_PCIE_CPU_DEV2_R_N at (A 2) is labeled only once in the design.
Signal RST_PCIE_CPU_DEV3_R_N at (A 2) is labeled only once in the design.
Signal      TP_RSVD_B1 at (B 3) is labeled only once in the design.
Signal FM_MEZZB_PRSNT1_N at (B 2) is labeled only once in the design.
Signal RST_PCIE_CPU_DEV1_R_N at (A 2) is labeled only once in the design.

Warnings in Page : @baseboard_fab2_lib.baseboard_fab2(sch_1):Page188
Signal TP_SHARED_KR_MDIO_0 at (B 2) is labeled only once in the design.
Signal TP_SHARED_KR_MDC_0 at (B 2) is labeled only once in the design.
Signal      TP_RSVD<0> at (B 2) is labeled only once in the design.

Warnings in Page : @baseboard_fab2_lib.baseboard_fab2(sch_1):Page189
Signal      JTAG_TMS_R at (B 1) is labeled only once in the design.
Signal      JTAG_TDI_R at (B 1) is labeled only once in the design.
Signal P3V3_STBY_PLD_D at (B 1) is labeled only once in the design.
Signal      JTAG_TCK_R at (B 1) is labeled only once in the design.
Signal JTAG_PLD_TDI_MUX at (B 3) is labeled only once in the design.
Signal      JTAG_TDO_R at (B 1) is labeled only once in the design.
Signal JTAG_PLD_TDO_MUX at (B 3) is labeled only once in the design.
Signal BMC_JTAG_SEL_N_MUX at (B 3) is labeled only once in the design.

Warnings in Page : @baseboard_fab2_lib.baseboard_fab2(sch_1):Page190
Signal FM_PWR_BTN_R2_N at (B 3) is labeled only once in the design.
Signal TP_CPLD1_PL2B_L_GPLLC_IN at (B 4) is labeled only once in the design.
Signal TP_CPLD1_PL1A_L_GPLLT_FB at (B 4) is labeled only once in the design.
Signal TP_CPLD1_PB5A_CSSPIN at (B 2) is labeled only once in the design.
Signal TP_CPLD1_PB8B_SO_SPISO at (B 2) is labeled only once in the design.
Signal TP_CPLD1_PB8A_MCLK_CCLK at (B 2) is labeled only once in the design.
Signal TP_CPLD1_PB25B_SI_SISPI at (A 2) is labeled only once in the design.
Signal TP_CPLD1_PB16A_PCLKT2_1 at (A 2) is labeled only once in the design.
Signal TP_CPLD1_PL7D_PCLKT4_0 at (A 4) is labeled only once in the design.
Signal  TP_CPLD1_PL11A at (A 4) is labeled only once in the design.
Signal TP_CPLD1_PB16B_PCLKC2_1 at (A 2) is labeled only once in the design.
Signal TP_CPLD1_PL1B_L_GPLLC_FB at (B 4) is labeled only once in the design.

Warnings in Page : @baseboard_fab2_lib.baseboard_fab2(sch_1):Page191
Signal PU_CPLD1_PT20D_PROGRAMN at (A 2) is labeled only once in the design.
Signal SGPIO_BMC_DIN_R at (B 2) is labeled only once in the design.
Signal RST_BMC_SYSRST_BTN_OUT_B_R1_N at (B 3) is labeled only once in the design.
Signal PU_FAB2_MARKER_CPLD at (A 3) is labeled only once in the design.
Signal  TP_CPLD1_PT11B at (B 2) is labeled only once in the design.
Signal FM_ADR_SMI_GPIO_R_N at (B 2) is labeled only once in the design.
Signal  TP_CPLD1_PT22C at (A 2) is labeled only once in the design.
Signal FM_PCH_PWRBTN_R1_N at (A 2) is labeled only once in the design.
Signal  TP_CPLD1_PT22D at (A 2) is labeled only once in the design.
Signal  TP_CPLD1_PT20B at (A 2) is labeled only once in the design.
Signal  TP_CPLD1_PT20A at (A 2) is labeled only once in the design.
Signal  TP_CPLD1_PT19D at (A 2) is labeled only once in the design.
Signal  TP_CPLD1_PT16B at (B 2) is labeled only once in the design.
Signal TP_CPLD1_PT17B_PCLKC0_1 at (B 2) is labeled only once in the design.
Signal  TP_CPLD1_PT17C at (B 2) is labeled only once in the design.
Signal TP_CPLD1_PR7A_PCLKT1_0 at (B 3) is labeled only once in the design.
Signal TP_CPLD1_PR7B_PCLKC1_0 at (B 3) is labeled only once in the design.
Signal   TP_CPLD1_PR7C at (B 3) is labeled only once in the design.
Signal   TP_CPLD1_PR7D at (B 3) is labeled only once in the design.
Signal   TP_CPLD1_PR9A at (B 3) is labeled only once in the design.
Signal   TP_CPLD1_PR9C at (A 3) is labeled only once in the design.
Signal   TP_CPLD1_PR9D at (A 3) is labeled only once in the design.
Signal  TP_CPLD1_PR10C at (A 3) is labeled only once in the design.
Signal  TP_CPLD1_PR11B at (A 3) is labeled only once in the design.
Signal  TP_CPLD1_PR12D at (A 3) is labeled only once in the design.
Signal  TP_CPLD1_PT13A at (B 2) is labeled only once in the design.
Signal  TP_CPLD1_PT11A at (B 2) is labeled only once in the design.
Signal TP_CPLD1_PT24D_DONE at (A 2) is labeled only once in the design.
Signal TP_CPLD1_PT24C_INITN at (A 2) is labeled only once in the design.
Signal  TP_CPLD1_PT24B at (A 2) is labeled only once in the design.

Warnings in Page : @baseboard_fab2_lib.baseboard_fab2(sch_1):Page193
Signal VR_PVCCMCP_CPU1_XADDR2 at (A 4) is labeled only once in the design.
Signal VR_PVCCIOMCP_CPU1_XADDR1 at (A 4) is labeled only once in the design.

Warnings in Page : @baseboard_fab2_lib.baseboard_fab2(sch_1):Page194
Signal VR_PVCCMCP_CPU0_XADDR2 at (A 4) is labeled only once in the design.
Signal VR_PVCCIOMCP_CPU0_XADDR1 at (A 4) is labeled only once in the design.
Signal CLK_322M_156M_CPU0_OSC_VRM_DP at (B 3) has too little display space.

Warnings in Page : @baseboard_fab2_lib.baseboard_fab2(sch_1):Page196
Signal VSENSE_P12V_ADM1085 at (B 2) is labeled only once in the design.
Signal  P3V_BAT_SOURCE at (B 4) is labeled only once in the design.
Signal  A_ADM1085_CEXT at (B 1) is labeled only once in the design.
Signal     PWRGD_P5V_R at (A 1) is labeled only once in the design.
Signal PWRGD_P12V_HSC_DLY_R at (B 1) is labeled only once in the design.
Signal     PWRGD_P5V_N at (A 2) is labeled only once in the design.
Signal   PWRGD_P3V3_R1 at (A 2) is labeled only once in the design.
Signal PWRGD_P12V_MAIN_R at (A 1) is labeled only once in the design.
Signal        A_PG_P5V at (A 3) is labeled only once in the design.
Signal  A_PG_P12V_MAIN at (A 3) is labeled only once in the design.
Signal  PWRGD_P12V_HSC at (B 2) has too little display space.

Warnings in Page : @baseboard_fab2_lib.baseboard_fab2(sch_1):Page197
Signal P12V_NVDIMM_ABC_D at (B 4) is labeled only once in the design.
Signal P12V_NVDIMM_KLM_D at (A 3) is labeled only once in the design.
Signal P12V_NVDIMM_GHJ_D at (B 3) is labeled only once in the design.
Signal PWRGD_PVDDQ_GHJ_N at (B 3) is labeled only once in the design.
Signal PWRGD_PVDDQ_KLM_N at (A 3) is labeled only once in the design.
Signal PWRGD_PVDDQ_DEF_N at (A 4) is labeled only once in the design.
Signal P12V_NVDIMM_DEF_D at (A 4) is labeled only once in the design.
Signal PWRGD_PVDDQ_ABC_N at (B 4) is labeled only once in the design.

Warnings in Page : @baseboard_fab2_lib.baseboard_fab2(sch_1):Page198
Signal TP_SLG55021_P5V_8 at (B 2) is labeled only once in the design.
Signal TP_SLG55021_P12V_MAIN_8 at (A 3) is labeled only once in the design.
Signal   P12V_SWITCH_G at (A 3) is labeled only once in the design.
Signal    P5V_SWITCH_G at (B 2) is labeled only once in the design.
Signal P12V_FAN_SWITCH_G at (A 2) is labeled only once in the design.
Signal TP_SLG55021_P12V_FAN_8 at (A 1) is labeled only once in the design.
Signal   P3V3_SWITCH_G at (B 4) is labeled only once in the design.
Signal TP_SLG55021_P3V3_8 at (B 3) is labeled only once in the design.

Warnings in Page : @baseboard_fab2_lib.baseboard_fab2(sch_1):Page199
Signal    P12V_HSC_VCC at (B 3) is labeled only once in the design.
Signal        A_HSC_UV at (B 3) is labeled only once in the design.
Signal        A_HSC_OV at (B 3) is labeled only once in the design.
Signal      A_HSC_PSET at (B 3) is labeled only once in the design.
Signal      A_HSC_ISET at (B 3) is labeled only once in the design.
Signal      A_HSC_VCAP at (B 3) is labeled only once in the design.
Signal   TP_HSC_SPISSN at (B 3) is labeled only once in the design.
Signal    A_HSC_ISET_S at (A 4) is labeled only once in the design.
Signal   A_HSC_ISET_S2 at (A 3) is labeled only once in the design.
Signal     A_HSC_PWGIN at (A 4) is labeled only once in the design.
Signal FM_P12V_HSC_ADR1 at (B 3) is labeled only once in the design.
Signal FM_P12V_HSC_ADR2 at (B 3) is labeled only once in the design.
Signal    A_HSC_ISTART at (B 3) is labeled only once in the design.
Signal IRQ_HSC_FAULT_R_N at (A 2) is labeled only once in the design.
Signal   A_HSC_OCP_SEL at (A 4) is labeled only once in the design.
Signal    PWRGD_P12V_R at (A 2) is labeled only once in the design.
Signal  PD_HSC_RETRY_N at (B 3) is labeled only once in the design.
Signal SMB_3V3SB_HSC_SCL_R at (B 3) is labeled only once in the design.
Signal SMB_3V3SB_HSC_SDA_R at (B 3) is labeled only once in the design.
Signal TP_HSC_ALERT2_N at (B 1) is labeled only once in the design.
Signal      A_HSC_VOUT at (B 1) is labeled only once in the design.
Signal   TEMP_SENSOR_B at (A 1) is labeled only once in the design.
Signal     TP_HSC_MCLK at (B 1) is labeled only once in the design.
Signal     TP_HSC_MDAT at (B 1) is labeled only once in the design.
Signal   TEMP_SENSOR_E at (A 1) is labeled only once in the design.
Signal      A_HSC_TEMP at (A 2) is labeled only once in the design.
Signal    A_HSC_LOW_EN at (A 4) is labeled only once in the design.
Signal   A_HSC_HIGH_EN at (A 4) has too little display space.

Warnings in Page : @baseboard_fab2_lib.baseboard_fab2(sch_1):Page200
Signal      A_HSC_HIGH at (B 4) is labeled only once in the design.
Signal FM_OC_DETECT_EN at (A 4) is labeled only once in the design.
Signal       A_HSC_LOW at (B 4) is labeled only once in the design.
Signal         A_HSC_C at (B 2) is labeled only once in the design.
Signal     P12V_MB0_SW at (B 1) is labeled only once in the design.
Signal  P12V_HSC_SENN0 at (B 1) is labeled only once in the design.
Signal A_HSC_LOW_DRAIN at (B 3) is labeled only once in the design.
Signal  P12V_HSC_SENP0 at (B 2) is labeled only once in the design.
Signal  P12V_HSC_SENN1 at (B 1) is labeled only once in the design.
Signal   A_HSC_GATE2_R at (B 1) is labeled only once in the design.
Signal   A_HSC_GATE3_R at (B 1) is labeled only once in the design.
Signal  P12V_HSC_SENP1 at (B 2) is labeled only once in the design.
Signal   A_HSC_TIMER_R at (A 4) is labeled only once in the design.
Signal      A_HSC_INAP at (A 4) is labeled only once in the design.
Signal   A_HSC_GATE1_R at (B 1) is labeled only once in the design.
Signal A_P12V_STBY_FPH_GATE at (A 2) is labeled only once in the design.
Signal   UV_HIGH_SET_N at (B 3) is labeled only once in the design.
Signal A_P12V_STBY_ADR_TRIGGER at (A 3) is labeled only once in the design.
Signal  A_HSC_LOW_GATE at (B 4) has too little display space.

Warnings in Page : @baseboard_fab2_lib.baseboard_fab2(sch_1):Page201
Signal VR_PVCCIN_CPU0_XADDR2 at (A 3) is labeled only once in the design.
Signal VR_PVCCIN_CPU0_VDD at (B 2) is labeled only once in the design.
Signal VR_PVCCIN_CPU0_VREN at (A 3) is labeled only once in the design.
Signal VSENSE_PVCCIN_CPU0_AVSP at (B 3) is labeled only once in the design.
Signal VSENSE_PVSA_CPU0_BVSP at (A 3) is labeled only once in the design.
Signal VR_VRRDY_PVCCIN_CPU0 at (B 2) is labeled only once in the design.
Signal VR_PVCCIN_CPU0_XADDR1 at (A 3) is labeled only once in the design.
Signal PU_VR_PVCCIN_CPU0_FLT1_SMBALT_N_IMON at (B 2) is labeled only once in the design.
Signal SVID_VALERT_VCCIN_CPU0 at (B 2) is labeled only once in the design.
Signal SVID_VDIO_PVCCIN_CPU0 at (B 2) is labeled only once in the design.
Signal PWRGD_PVSA_CPU0_R at (B 2) is labeled only once in the design.
Signal PU_VR_PVCCIN_CPU0_IMON at (B 2) is labeled only once in the design.
Signal IRQ_PVCCIN_CPU0_VRHOT_LVC3_R_N at (B 2) is labeled only once in the design.
Signal SVID_VCLK_PVCCIN_CPU0 at (B 3) is labeled only once in the design.

Warnings in Page : @baseboard_fab2_lib.baseboard_fab2(sch_1):Page202
Signal VR_PVCCIN_CPU0_PH1_PHASE at (B 3) is labeled only once in the design.
Signal VR_PVCCIN_CPU0_PH1_BOOT_R at (B 3) is labeled only once in the design.
Signal TP_PVCCIN_CPU0_PH1_GL_1 at (B 3) is labeled only once in the design.
Signal VR_PVCCIN_CPU0_PH1_VCIN at (B 3) is labeled only once in the design.
Signal VR_PVCCIN_CPU0_PH2_BOOT at (A 3) is labeled only once in the design.
Signal VR_PVCCIN_CPU0_PH2_BOOT_R at (A 3) is labeled only once in the design.
Signal VR_PVCCIN_CPU0_PH1_BOOT at (B 3) is labeled only once in the design.
Signal VR_PVCCIN_CPU0_PH1_OCSET at (B 2) is labeled only once in the design.
Signal TP_PVCCIN_CPU0_PH1_GL_0 at (B 3) is labeled only once in the design.
Signal VR_PVCCIN_CPU0_PH2_OCSET at (A 2) is labeled only once in the design.
Signal VR_PVCCIN_CPU0_PHASE1_RC at (B 1) is labeled only once in the design.
Signal VR_PVCCIN_CPU0_PHASE1 at (B 2) is labeled only once in the design.
Signal VR_PVCCIN_CPU0_PHASE2_RC at (A 1) is labeled only once in the design.
Signal VR_PVCCIN_CPU0_PH2_VCIN at (A 3) is labeled only once in the design.
Signal VR_PVCCIN_CPU0_PH2_PHASE at (A 3) is labeled only once in the design.
Signal TP_PVCCIN_CPU0_PH2_GL_1 at (A 3) is labeled only once in the design.
Signal TP_PVCCIN_CPU0_PH2_GL_0 at (A 3) is labeled only once in the design.
Signal VR_PVCCIN_CPU0_PHASE2 at (A 2) is labeled only once in the design.

Warnings in Page : @baseboard_fab2_lib.baseboard_fab2(sch_1):Page203
Signal VR_PVCCIN_CPU0_PH4_VCIN at (A 3) is labeled only once in the design.
Signal VR_PVCCIN_CPU0_PHASE4_RC at (A 1) is labeled only once in the design.
Signal VR_PVCCIN_CPU0_PH3_BOOT at (B 3) is labeled only once in the design.
Signal VR_PVCCIN_CPU0_PH3_OCSET at (B 2) is labeled only once in the design.
Signal VR_PVCCIN_CPU0_PH4_PHASE at (A 3) is labeled only once in the design.
Signal VR_PVCCIN_CPU0_PH4_BOOT at (A 3) is labeled only once in the design.
Signal VR_PVCCIN_CPU0_PH3_PHASE at (B 3) is labeled only once in the design.
Signal TP_PVCCIN_CPU0_PH3_GL_0 at (B 3) is labeled only once in the design.
Signal TP_PVCCIN_CPU0_PH3_GL_1 at (B 3) is labeled only once in the design.
Signal VR_PVCCIN_CPU0_PH3_BOOT_R at (B 3) is labeled only once in the design.
Signal VR_PVCCIN_CPU0_PH3_VCIN at (B 3) is labeled only once in the design.
Signal VR_PVCCIN_CPU0_PH4_BOOT_R at (A 3) is labeled only once in the design.
Signal TP_PVCCIN_CPU0_PH4_GL_0 at (A 3) is labeled only once in the design.
Signal TP_PVCCIN_CPU0_PH4_GL_1 at (A 3) is labeled only once in the design.
Signal VR_PVCCIN_CPU0_PHASE3_RC at (B 1) is labeled only once in the design.
Signal VR_PVCCIN_CPU0_PHASE4 at (A 2) is labeled only once in the design.
Signal VR_PVCCIN_CPU0_PHASE3 at (B 2) is labeled only once in the design.
Signal VR_PVCCIN_CPU0_PH4_OCSET at (A 2) is labeled only once in the design.

Warnings in Page : @baseboard_fab2_lib.baseboard_fab2(sch_1):Page204
Signal VR_PVCCIN_CPU0_PH5_VCIN at (B 3) is labeled only once in the design.
Signal TP_PVCCIN_CPU0_PH5_GL_1 at (B 3) is labeled only once in the design.
Signal VR_PVCCIN_CPU0_PHASE5 at (B 2) is labeled only once in the design.
Signal VR_PVCCIN_CPU0_PH5_BOOT_R at (B 3) is labeled only once in the design.
Signal VR_PVCCIN_CPU0_PH5_BOOT at (B 3) is labeled only once in the design.
Signal TP_PVCCIN_CPU0_PH5_GL_0 at (B 3) is labeled only once in the design.
Signal VR_PVCCIN_CPU0_PH5_OCSET at (B 2) is labeled only once in the design.
Signal VR_PVCCIN_CPU0_PH5_PHASE at (B 3) is labeled only once in the design.
Signal VR_PVCCIN_CPU0_PHASE5_RC at (B 1) is labeled only once in the design.

Warnings in Page : @baseboard_fab2_lib.baseboard_fab2(sch_1):Page205
Signal VR_PVSA_CPU0_VCIN at (B 3) is labeled only once in the design.
Signal VR_PVSA_CPU0_PHASE at (B 3) is labeled only once in the design.
Signal VR_PVSA_CPU0_BOOT at (B 4) is labeled only once in the design.
Signal VR_PVSA_CPU0_BOOT_R at (B 3) is labeled only once in the design.
Signal TP_PVSA_CPU0_GL_0 at (B 3) is labeled only once in the design.
Signal VR_PVSA_CPU0_OCSET at (B 2) is labeled only once in the design.
Signal TP_PVSA_CPU0_GL_1 at (B 3) is labeled only once in the design.
Signal VR_PVSA_CPU0_PHASE_SW_RC at (B 1) is labeled only once in the design.
Signal VR_PVSA_CPU0_PHASE_SW at (B 2) is labeled only once in the design.

Warnings in Page : @baseboard_fab2_lib.baseboard_fab2(sch_1):Page206
Signal VR_PVCCIN_CPU1_XADDR2 at (A 3) is labeled only once in the design.
Signal VR_VRRDY_PVCCIN_CPU1 at (B 2) is labeled only once in the design.
Signal PU_VR_PVCCIN_CPU1_FLT1_SMBALT_N_IMON at (B 2) is labeled only once in the design.
Signal PU_VR_PVCCIN_CPU1_IMON at (B 2) is labeled only once in the design.
Signal SVID_VDIO_PVCCIN_CPU1 at (B 2) is labeled only once in the design.
Signal SVID_VALERT_VCCIN_CPU1 at (B 2) is labeled only once in the design.
Signal IRQ_PVCCIN_CPU1_VRHOT_LVC3_R_N at (B 2) is labeled only once in the design.
Signal PWRGD_PVSA_CPU1_R at (B 2) is labeled only once in the design.
Signal VR_PVCCIN_CPU1_VDD at (B 3) is labeled only once in the design.
Signal SVID_VCLK_PVCCIN_CPU1 at (B 3) is labeled only once in the design.
Signal VSENSE_PVCCIN_CPU1_AVSP at (B 3) is labeled only once in the design.
Signal VR_PVCCIN_CPU1_VREN at (A 3) is labeled only once in the design.
Signal VSENSE_PVSA_CPU1_BVSP at (A 3) is labeled only once in the design.
Signal VR_PVCCIN_CPU1_XADDR1 at (A 3) is labeled only once in the design.

Warnings in Page : @baseboard_fab2_lib.baseboard_fab2(sch_1):Page207
Signal VR_PVCCIN_CPU1_PH2_BOOT_R at (A 3) is labeled only once in the design.
Signal VR_PVCCIN_CPU1_PH2_PHASE at (A 3) is labeled only once in the design.
Signal VR_PVCCIN_CPU1_PH2_BOOT at (A 3) is labeled only once in the design.
Signal VR_PVCCIN_CPU1_PH1_VCIN at (B 3) is labeled only once in the design.
Signal VR_PVCCIN_CPU1_PHASE2_RC at (A 2) is labeled only once in the design.
Signal VR_PVCCIN_CPU1_PH1_BOOT_R at (B 3) is labeled only once in the design.
Signal VR_PVCCIN_CPU1_PHASE1 at (B 2) is labeled only once in the design.
Signal VR_PVCCIN_CPU1_PH1_PHASE at (B 3) is labeled only once in the design.
Signal TP_PVCCINC_CPU1_PH1_GL_1 at (B 3) is labeled only once in the design.
Signal VR_PVCCIN_CPU1_PHASE1_RC at (B 1) is labeled only once in the design.
Signal TP_PVCCINC_CPU1_PH1_GL_0 at (B 3) is labeled only once in the design.
Signal VR_PVCCIN_CPU1_PH1_OCSET at (B 2) is labeled only once in the design.
Signal VR_PVCCIN_CPU1_PH1_BOOT at (B 3) is labeled only once in the design.
Signal TP_PVCCINC_CPU1_PH2_GL_1 at (A 3) is labeled only once in the design.
Signal TP_PVCCINC_CPU1_PH2_GL_0 at (A 3) is labeled only once in the design.
Signal VR_PVCCIN_CPU1_PH2_VCIN at (A 3) is labeled only once in the design.
Signal VR_PVCCIN_CPU1_PHASE2 at (A 2) is labeled only once in the design.
Signal VR_PVCCIN_CPU1_PH2_OCSET at (A 2) is labeled only once in the design.

Warnings in Page : @baseboard_fab2_lib.baseboard_fab2(sch_1):Page208
Signal VR_PVCCIN_CPU1_PHASE4_RC at (A 1) is labeled only once in the design.
Signal VR_PVCCIN_CPU1_PHASE3_RC at (B 1) is labeled only once in the design.
Signal VR_PVCCIN_CPU1_PHASE4 at (A 2) is labeled only once in the design.
Signal VR_PVCCIN_CPU1_PHASE3 at (B 2) is labeled only once in the design.
Signal VR_PVCCIN_CPU1_PH3_OCSET at (B 2) is labeled only once in the design.
Signal VR_PVCCIN_CPU1_PH4_PHASE at (A 3) is labeled only once in the design.
Signal VR_PVCCIN_CPU1_PH3_PHASE at (B 3) is labeled only once in the design.
Signal TP_PVCCIN_CPU1_PH4_GL_1 at (A 3) is labeled only once in the design.
Signal VR_PVCCIN_CPU1_PH4_BOOT at (A 3) is labeled only once in the design.
Signal VR_PVCCIN_CPU1_PH3_BOOT at (B 4) is labeled only once in the design.
Signal TP_PVCCIN_CPU1_PH3_GL_1 at (B 3) is labeled only once in the design.
Signal TP_PVCCIN_CPU1_PH3_GL_0 at (B 3) is labeled only once in the design.
Signal TP_PVCCIN_CPU1_PH4_GL_0 at (A 3) is labeled only once in the design.
Signal VR_PVCCIN_CPU1_PH3_BOOT_R at (B 3) is labeled only once in the design.
Signal VR_PVCCIN_CPU1_PH3_VCIN at (B 3) is labeled only once in the design.
Signal VR_PVCCIN_CPU1_PH4_BOOT_R at (A 3) is labeled only once in the design.
Signal VR_PVCCIN_CPU1_PH4_VCIN at (A 3) is labeled only once in the design.
Signal VR_PVCCIN_CPU1_PH4_OCSET at (A 2) is labeled only once in the design.

Warnings in Page : @baseboard_fab2_lib.baseboard_fab2(sch_1):Page209
Signal VR_PVCCIN_CPU1_PH5_VCIN at (B 3) is labeled only once in the design.
Signal TP_PVCCIN_CPU1_PH5_GL_0 at (B 3) is labeled only once in the design.
Signal VR_PVCCIN_CPU1_PH5_PHASE at (B 3) is labeled only once in the design.
Signal VR_PVCCIN_CPU1_PH5_BOOT at (B 3) is labeled only once in the design.
Signal VR_PVCCIN_CPU1_PHASE5 at (B 2) is labeled only once in the design.
Signal VR_PVCCIN_CPU1_PH5_OCSET at (B 2) is labeled only once in the design.
Signal TP_PVCCIN_CPU1_PH5_GL_1 at (B 3) is labeled only once in the design.
Signal VR_PVCCIN_CPU1_PHASE5_RC at (B 1) is labeled only once in the design.
Signal VR_PVCCIN_CPU1_PH5_BOOT_R at (B 3) is labeled only once in the design.

Warnings in Page : @baseboard_fab2_lib.baseboard_fab2(sch_1):Page210
Signal VR_PVSA_CPU1_PHASE_SW_RC at (B 1) is labeled only once in the design.
Signal VR_PVSA_CPU1_BOOT at (B 4) is labeled only once in the design.
Signal TP_PVSA_CPU1_GL_1 at (B 3) is labeled only once in the design.
Signal VR_PVSA_CPU1_PHASE_SW at (B 2) is labeled only once in the design.
Signal TP_PVSA_CPU1_GL_0 at (B 3) is labeled only once in the design.
Signal VR_PVSA_CPU1_BOOT_R at (B 3) is labeled only once in the design.
Signal VR_PVSA_CPU1_PHASE at (B 4) is labeled only once in the design.
Signal VR_PVSA_CPU1_OCSET at (B 2) is labeled only once in the design.
Signal VR_PVSA_CPU1_VCIN at (B 3) is labeled only once in the design.

Warnings in Page : @baseboard_fab2_lib.baseboard_fab2(sch_1):Page211
Signal VR_PVCCIO_CPU0_XADDR1 at (A 3) is labeled only once in the design.
Signal VR_PVCCIO_CPU0_VDD at (B 3) is labeled only once in the design.
Signal IRQ_PVCCIO_CPU0_VRHOT_N at (B 2) is labeled only once in the design.
Signal PWRGD_PVCCIO_CPU0_R at (B 2) is labeled only once in the design.
Signal VR_PVCCIO_CPU0_AVSP at (B 4) is labeled only once in the design.
Signal SVID_VDIO_PVCCIO_CPU0 at (B 3) is labeled only once in the design.
Signal SVID_ALERT_PVCCIO_CPU0 at (B 2) is labeled only once in the design.
Signal PU_VR_PVCCIO_CPU0_FAULT1 at (B 2) is labeled only once in the design.
Signal VR_PVCCIO_CPU0_XADDR2 at (A 3) is labeled only once in the design.
Signal VR_PVCCIO_CPU0_EN at (B 3) is labeled only once in the design.
Signal SVID_CLK_PVCCIO_CPU0 at (B 3) is labeled only once in the design.
Signal SMB_VR_STBY_LVC3_SCL at (A 4) has too little display space.

Warnings in Page : @baseboard_fab2_lib.baseboard_fab2(sch_1):Page212
Signal VR_PVCCIO_CPU0_PH1_BOOT at (B 3) is labeled only once in the design.
Signal VR_PVCCIO_CPU0_PH1_PHASE at (B 3) is labeled only once in the design.
Signal VR_PVCCIO_CPU0_PH1_SW_RC at (B 2) is labeled only once in the design.
Signal TP_PVCCIO_CPU0_GL_1 at (B 3) is labeled only once in the design.
Signal TP_PVCCIO_CPU0_GL_0 at (B 3) is labeled only once in the design.
Signal VR_PVCCIO_CPU0_PH1_VCIN at (B 3) is labeled only once in the design.
Signal VR_PVCCIO_CPU0_PH1_SW at (B 2) is labeled only once in the design.
Signal VR_PVCCIO_CPU0_OCSET at (B 2) is labeled only once in the design.
Signal VR_PVCCIO_CPU0_PH1_BOOT_R at (B 3) is labeled only once in the design.

Warnings in Page : @baseboard_fab2_lib.baseboard_fab2(sch_1):Page213
Signal VR_PVCCIO_CPU1_XADDR1 at (A 3) is labeled only once in the design.
Signal VR_PVCCIO_CPU1_VDD at (B 3) is labeled only once in the design.
Signal SVID_CLK_PVCCIO_CPU1 at (B 3) is labeled only once in the design.
Signal PWRGD_PVCCIO_CPU1_R at (B 2) is labeled only once in the design.
Signal PU_VR_PVCCIO_CPU1_FAULT1 at (B 2) is labeled only once in the design.
Signal SVID_ALERT_PVCCIO_CPU1 at (B 2) is labeled only once in the design.
Signal IRQ_PVCCIO_CPU1_VRHOT_N at (B 2) is labeled only once in the design.
Signal VR_PVCCIO_CPU1_AVSP at (A 4) is labeled only once in the design.
Signal VR_PVCCIO_CPU1_XADDR2 at (A 3) is labeled only once in the design.
Signal SVID_VDIO_PVCCIO_CPU1 at (B 3) is labeled only once in the design.
Signal VR_PVCCIO_CPU1_EN at (B 3) is labeled only once in the design.
Signal SMB_VR_STBY_LVC3_SCL at (A 4) has too little display space.

Warnings in Page : @baseboard_fab2_lib.baseboard_fab2(sch_1):Page214
Signal VR_PVCCIO_CPU1_PH1_BOOT_R at (B 3) is labeled only once in the design.
Signal VR_PVCCIO_CPU1_PH1_BOOT at (B 3) is labeled only once in the design.
Signal VR_PVCCIO_CPU1_OCSET at (B 2) is labeled only once in the design.
Signal TP_PVCCIO_CPU1_GL_0 at (B 3) is labeled only once in the design.
Signal TP_PVCCIO_CPU1_GL_1 at (B 3) is labeled only once in the design.
Signal VR_PVCCIO_CPU1_PH1_SW_RC at (B 1) is labeled only once in the design.
Signal VR_PVCCIO_CPU1_PH1_VCIN at (B 3) is labeled only once in the design.
Signal VR_PVCCIO_CPU1_PH1_PHASE at (B 3) is labeled only once in the design.
Signal VR_PVCCIO_CPU1_PH1_SW at (B 2) is labeled only once in the design.

Warnings in Page : @baseboard_fab2_lib.baseboard_fab2(sch_1):Page215
Signal SVID_CLK_PVDDQ_ABC at (B 3) is labeled only once in the design.
Signal TP_PVDDQ_ABC_MP1 at (B 2) is labeled only once in the design.
Signal PU_VR_PVDDQ_ABC_FAULT1 at (B 2) is labeled only once in the design.
Signal VR_PVDDQ_ABC_AVSP at (A 4) is labeled only once in the design.
Signal TP_PVDDQ_ABC_MP2 at (B 2) is labeled only once in the design.
Signal VR_PVDDQ_ABC_VREN at (A 3) is labeled only once in the design.
Signal SVID_ALERT_PVDDQ_ABC at (B 2) is labeled only once in the design.
Signal VR_PVDDQ_ABC_VDD at (B 3) is labeled only once in the design.
Signal VR_PVDDQ_ABC_XADDR1 at (A 3) is labeled only once in the design.
Signal VR_PVDDQ_ABC_XADDR2 at (A 3) is labeled only once in the design.
Signal SVID_VDIO_PVDDQ_ABC at (B 2) is labeled only once in the design.
Signal IRQ_PVDDQ_ABC_VRHOT_LVT3_R_N at (B 2) is labeled only once in the design.

Warnings in Page : @baseboard_fab2_lib.baseboard_fab2(sch_1):Page216
Signal VR_PVDDQ_ABC_PH2_BOOT at (A 4) is labeled only once in the design.
Signal VR_PVDDQ_ABC_PH2_PHASE at (A 4) is labeled only once in the design.
Signal VR_PVDDQ_ABC_PH2_VCIN at (A 4) is labeled only once in the design.
Signal VR_PVDDQ_ABC_PH1_PHASE at (B 3) is labeled only once in the design.
Signal VR_PVDDQ_ABC_PH1_VCIN at (B 4) is labeled only once in the design.
Signal VR_PVDDQ_ABC_PH1_BOOT at (B 3) is labeled only once in the design.
Signal TP_PVDDQ_ABC_PH2_GL_0 at (A 3) is labeled only once in the design.
Signal VR_PVDDQ_ABC_PH2_BOOT_R at (A 3) is labeled only once in the design.
Signal VR_PVDDQ_ABC_PH2_SW at (A 2) is labeled only once in the design.
Signal VR_PVDDQ_ABC_PH2_SW_RC at (A 1) is labeled only once in the design.
Signal TP_PVDDQ_ABC_PH2_GL_1 at (A 3) is labeled only once in the design.
Signal TP_PVDDQ_ABC_PH1_GL_1 at (B 3) is labeled only once in the design.
Signal TP_PVDDQ_ABC_PH1_GL_0 at (B 3) is labeled only once in the design.
Signal VR_PVDDQ_ABC_PH1_BOOT_R at (B 3) is labeled only once in the design.
Signal VR_PVDDQ_ABC_PH2_OCSET at (A 2) is labeled only once in the design.
Signal VR_PVDDQ_ABC_PH1_SW at (B 2) is labeled only once in the design.
Signal VR_PVDDQ_ABC_PH1_SW_RC at (B 1) is labeled only once in the design.
Signal VR_PVDDQ_ABC_PH1_OCSET at (B 2) is labeled only once in the design.

Warnings in Page : @baseboard_fab2_lib.baseboard_fab2(sch_1):Page218
Signal VR_PVDDQ_DEF_VREN at (A 3) is labeled only once in the design.
Signal SVID_CLK_PVDDQ_DEF at (B 3) is labeled only once in the design.
Signal VR_PVDDQ_DEF_XADDR1 at (A 3) is labeled only once in the design.
Signal VR_PVDDQ_DEF_XADDR2 at (A 3) is labeled only once in the design.
Signal TP_PVDDQ_DEF_MP1 at (B 2) is labeled only once in the design.
Signal TP_PVDDQ_DEF_MP2 at (B 2) is labeled only once in the design.
Signal VR_PVDDQ_DEF_VDD at (B 3) is labeled only once in the design.
Signal VR_PVDDQ_DEF_AVSP at (A 4) is labeled only once in the design.
Signal IRQ_PVDDQ_DEF_VRHOT_LVT3_R_N at (B 2) is labeled only once in the design.
Signal SVID_ALERT_PVDDQ_DEF at (B 2) is labeled only once in the design.
Signal PU_VR_PVDDQ_DEF_FAULT1 at (B 2) is labeled only once in the design.
Signal SVID_VDIO_PVDDQ_DEF at (A 2) is labeled only once in the design.

Warnings in Page : @baseboard_fab2_lib.baseboard_fab2(sch_1):Page219
Signal VR_PVDDQ_DEF_PH1_SW at (B 2) is labeled only once in the design.
Signal VR_PVDDQ_DEF_PH1_OCSET at (B 2) is labeled only once in the design.
Signal VR_PVDDQ_DEF_PH1_BOOT_R at (B 3) is labeled only once in the design.
Signal VR_PVDDQ_DEF_PH1_VCIN at (B 4) is labeled only once in the design.
Signal VR_PVDDQ_DEF_PH1_PHASE at (B 4) is labeled only once in the design.
Signal VR_PVDDQ_DEF_PH1_SW_RC at (B 2) is labeled only once in the design.
Signal VR_PVDDQ_DEF_PH2_PHASE at (A 4) is labeled only once in the design.
Signal TP_PVDDQ_DEF_PH1_GL_0 at (B 3) is labeled only once in the design.
Signal TP_PVDDQ_DEF_PH1_GL_1 at (B 3) is labeled only once in the design.
Signal VR_PVDDQ_DEF_PH1_BOOT at (B 4) is labeled only once in the design.
Signal VR_PVDDQ_DEF_PH2_BOOT at (A 4) is labeled only once in the design.
Signal VR_PVDDQ_DEF_PH2_SW_RC at (A 1) is labeled only once in the design.
Signal VR_PVDDQ_DEF_PH2_SW at (A 2) is labeled only once in the design.
Signal TP_PVDDQ_DEF_PH2_GL_0 at (A 3) is labeled only once in the design.
Signal TP_PVDDQ_DEF_PH2_GL_1 at (A 3) is labeled only once in the design.
Signal VR_PVDDQ_DEF_PH2_VCIN at (A 4) is labeled only once in the design.
Signal VR_PVDDQ_DEF_PH2_OCSET at (A 2) is labeled only once in the design.
Signal VR_PVDDQ_DEF_PH2_BOOT_R at (A 3) is labeled only once in the design.

Warnings in Page : @baseboard_fab2_lib.baseboard_fab2(sch_1):Page221
Signal FM_PVTT_ABC_EN_R at (A 4) is labeled only once in the design.
Signal VR_PVTT_ABC_BIAS at (B 3) is labeled only once in the design.
Signal VR_PVTT_ABC_SNS at (A 3) is labeled only once in the design.
Signal PWRGD_PVTT_ABC_CPU0_R at (B 2) is labeled only once in the design.
Signal VR_PVTT_ABC_VREF at (A 3) is labeled only once in the design.
Signal VSENSE_PVDDQ_ABC_VTT at (A 4) is labeled only once in the design.

Warnings in Page : @baseboard_fab2_lib.baseboard_fab2(sch_1):Page222
Signal PWRGD_PVTT_DEF_CPU0_R at (B 2) is labeled only once in the design.
Signal FM_PVTT_DEF_EN_R at (A 3) is labeled only once in the design.
Signal VSENSE_PVDDQ_DEF_VTT at (A 3) is labeled only once in the design.
Signal VR_PVTT_DEF_BIAS at (B 3) is labeled only once in the design.
Signal VR_PVTT_DEF_SNS at (A 3) is labeled only once in the design.
Signal VR_PVTT_DEF_VREF at (A 2) is labeled only once in the design.

Warnings in Page : @baseboard_fab2_lib.baseboard_fab2(sch_1):Page223
Signal TP_PVDDQ_GHJ_MP2 at (B 2) is labeled only once in the design.
Signal VR_PVDDQ_GHJ_AVSP at (A 4) is labeled only once in the design.
Signal VR_PVDDQ_GHJ_VREN at (A 4) is labeled only once in the design.
Signal VR_PVDDQ_GHJ_VDD at (B 3) is labeled only once in the design.
Signal SVID_VDIO_PVDDQ_GHJ at (B 2) is labeled only once in the design.
Signal TP_PVDDQ_GHJ_MP1 at (B 2) is labeled only once in the design.
Signal SVID_ALERT_PVDDQ_GHJ at (B 2) is labeled only once in the design.
Signal VR_PVDDQ_GHJ_XADDR2 at (A 3) is labeled only once in the design.
Signal VR_PVDDQ_GHJ_XADDR1 at (A 3) is labeled only once in the design.
Signal IRQ_PVDDQ_GHJ_VRHOT_LVT3_R_N at (B 2) is labeled only once in the design.
Signal PU_VR_PVDDQ_GHJ_FAULT1 at (B 2) is labeled only once in the design.
Signal SVID_CLK_PVDDQ_GHJ at (B 3) is labeled only once in the design.

Warnings in Page : @baseboard_fab2_lib.baseboard_fab2(sch_1):Page224
Signal VR_PVDDQ_GHJ_PH1_VCIN at (B 4) is labeled only once in the design.
Signal TP_PVDDQ_GHJ_PH1_GL_0 at (B 3) is labeled only once in the design.
Signal VR_PVDDQ_GHJ_PH2_PHASE at (A 3) is labeled only once in the design.
Signal TP_PVDDQ_GHJ_PH1_GL_1 at (B 3) is labeled only once in the design.
Signal VR_PVDDQ_GHJ_PH1_BOOT_R at (B 3) is labeled only once in the design.
Signal VR_PVDDQ_GHJ_PH1_OCSET at (B 2) is labeled only once in the design.
Signal VR_PVDDQ_GHJ_PH1_SW at (B 2) is labeled only once in the design.
Signal VR_PVDDQ_GHJ_PH1_SW_RC at (B 2) is labeled only once in the design.
Signal VR_PVDDQ_GHJ_PH2_VCIN at (A 4) is labeled only once in the design.
Signal VR_PVDDQ_GHJ_PH2_OCSET at (A 2) is labeled only once in the design.
Signal VR_PVDDQ_GHJ_PH2_SW at (A 2) is labeled only once in the design.
Signal TP_PVDDQ_GHJ_PH2_GL_1 at (A 3) is labeled only once in the design.
Signal TP_PVDDQ_GHJ_PH2_GL_0 at (A 3) is labeled only once in the design.
Signal VR_PVDDQ_GHJ_PH2_SW_RC at (A 2) is labeled only once in the design.
Signal VR_PVDDQ_GHJ_PH2_BOOT_R at (A 3) is labeled only once in the design.
Signal VR_PVDDQ_GHJ_PH2_BOOT at (A 4) is labeled only once in the design.
Signal VR_PVDDQ_GHJ_PH1_BOOT at (B 4) is labeled only once in the design.
Signal VR_PVDDQ_GHJ_PH1_PHASE at (B 4) is labeled only once in the design.

Warnings in Page : @baseboard_fab2_lib.baseboard_fab2(sch_1):Page226
Signal IRQ_PVDDQ_KLM_VRHOT_LVT3_R_N at (B 2) is labeled only once in the design.
Signal SVID_ALERT_PVDDQ_KLM at (B 2) is labeled only once in the design.
Signal NC_PVDDQ_KLM_GP0 at (B 2) is labeled only once in the design.
Signal VR_PVDDQ_KLM_VREN at (A 4) is labeled only once in the design.
Signal SVID_CLK_PVDDQ_KLM at (B 3) is labeled only once in the design.
Signal VR_PVDDQ_KLM_VDD at (B 3) is labeled only once in the design.
Signal VR_PVDDQ_KLM_XADDR1 at (A 3) is labeled only once in the design.
Signal VR_PVDDQ_KLM_XADDR2 at (A 3) is labeled only once in the design.
Signal VR_PVDDQ_KLM_AVSP at (A 4) is labeled only once in the design.
Signal NC_PVDDQ_KLM_GP1 at (B 2) is labeled only once in the design.
Signal PU_VR_PVDDQ_KLM_FAULT1 at (B 2) is labeled only once in the design.
Signal SVID_VDIO_PVDDQ_KLM at (B 2) is labeled only once in the design.

Warnings in Page : @baseboard_fab2_lib.baseboard_fab2(sch_1):Page227
Signal VR_PVDDQ_KLM_PH2_BOOT at (A 4) is labeled only once in the design.
Signal VR_PVDDQ_KLM_PH1_PHASE at (B 4) is labeled only once in the design.
Signal VR_PVDDQ_KLM_PH1_BOOT at (B 4) is labeled only once in the design.
Signal VR_PVDDQ_KLM_PH1_BOOT_R at (B 3) is labeled only once in the design.
Signal TP_PVDDQ_KLM_PH1_GL_1 at (B 3) is labeled only once in the design.
Signal VR_PVDDQ_KLM_PH1_OCSET at (B 2) is labeled only once in the design.
Signal VR_PVDDQ_KLM_PH1_SW at (B 2) is labeled only once in the design.
Signal TP_PVDDQ_KLM_PH1_GL_0 at (B 3) is labeled only once in the design.
Signal VR_PVDDQ_KLM_PH1_VCIN at (B 4) is labeled only once in the design.
Signal VR_PVDDQ_KLM_PH1_RC at (B 2) is labeled only once in the design.
Signal VR_PVDDQ_KLM_PH2_PHASE at (A 4) is labeled only once in the design.
Signal VR_PVDDQ_KLM_PH2_SW at (A 2) is labeled only once in the design.
Signal VR_PVDDQ_KLM_PH2_OCSET at (A 2) is labeled only once in the design.
Signal TP_PVDDQ_KLM_PH2_GL_0 at (A 3) is labeled only once in the design.
Signal VR_PVDDQ_KLM_PH2_VCIN at (A 4) is labeled only once in the design.
Signal VR_PVDDQ_KLM_PH2_BOOT_R at (A 3) is labeled only once in the design.
Signal VR_PVDDQ_KLM_PH2_RC at (A 1) is labeled only once in the design.
Signal TP_PVDDQ_KLM_PH2_GL_1 at (A 3) is labeled only once in the design.

Warnings in Page : @baseboard_fab2_lib.baseboard_fab2(sch_1):Page229
Signal PWRGD_PVTT_GHJ_CPU1_R at (B 2) is labeled only once in the design.
Signal VR_PVTT_GHJ_VREF at (A 3) is labeled only once in the design.
Signal VR_PVTT_GHJ_BIAS at (B 3) is labeled only once in the design.
Signal VSENSE_PVDDQ_GHJ_VTT at (A 3) is labeled only once in the design.
Signal FM_PVTT_GHJ_EN_R at (A 4) is labeled only once in the design.
Signal VR_PVTT_GHJ_SNS at (A 3) is labeled only once in the design.

Warnings in Page : @baseboard_fab2_lib.baseboard_fab2(sch_1):Page230
Signal VR_PVTT_KLM_VREF at (A 3) is labeled only once in the design.
Signal PWRGD_PVTT_KLM_CPU1_R at (B 2) is labeled only once in the design.
Signal VR_PVTT_KLM_BIAS at (B 3) is labeled only once in the design.
Signal VSENSE_PVDDQ_KLM_VTT at (A 4) is labeled only once in the design.
Signal FM_PVTT_KLM_EN_R at (A 3) is labeled only once in the design.
Signal VR_PVTT_KLM_SNS at (A 3) is labeled only once in the design.

Warnings in Page : @baseboard_fab2_lib.baseboard_fab2(sch_1):Page231
Signal VR_PVPP_ABC_ISET at (A 3) is labeled only once in the design.
Signal VR_COMP_PVPP_ABC at (A 1) is labeled only once in the design.
Signal VR_COMP_RC_PVPP_ABC at (B 2) is labeled only once in the design.
Signal FM_PVPP_PVDDQ_CPU0_EN_ABC at (B 3) is labeled only once in the design.
Signal  VR_VB_PVPP_ABC at (B 3) is labeled only once in the design.
Signal PWRGD_PVPP_ABC_R at (A 2) is labeled only once in the design.
Signal VR_FET_SW_P12V_STBY_PVPP_ABC at (B 3) is labeled only once in the design.
Signal VR_PVPP_ABC_BOOT at (B 2) is labeled only once in the design.
Signal VR_PVPP_ABC_PHASE at (B 2) is labeled only once in the design.
Signal VR_PVPP_ABC_SNUB at (B 2) is labeled only once in the design.
Signal VR_COMP_PVPP_ABC_3 at (B 2) is labeled only once in the design.
Signal VSENSE_PVPP_ABC at (A 1) is labeled only once in the design.
Signal VR_PVPP_ABC_BOOT_R at (B 2) is labeled only once in the design.
Signal  VR_FB_PVPP_ABC at (A 1) is labeled only once in the design.
Signal  VR_PVPP_ABC_SS at (A 3) is labeled only once in the design.

Warnings in Page : @baseboard_fab2_lib.baseboard_fab2(sch_1):Page232
Signal  VR_FB_PVPP_DEF at (A 1) is labeled only once in the design.
Signal VR_PVPP_DEF_SNUB at (B 2) is labeled only once in the design.
Signal VR_COMP_PVPP_DEF at (A 1) is labeled only once in the design.
Signal VR_COMP_PVPP_DEF_3 at (B 2) is labeled only once in the design.
Signal VSENSE_PVPP_DEF at (A 1) is labeled only once in the design.
Signal VR_COMP_RC_PVPP_DEF at (A 2) is labeled only once in the design.
Signal VR_PVPP_DEF_BOOT_R at (B 2) is labeled only once in the design.
Signal VR_PVPP_DEF_BOOT at (B 2) is labeled only once in the design.
Signal PWRGD_PVPP_DEF_R at (A 2) is labeled only once in the design.
Signal  VR_PVPP_DEF_SS at (A 3) is labeled only once in the design.
Signal FM_PVPP_PVDDQ_CPU0_EN_DEF at (B 3) is labeled only once in the design.
Signal  VR_VB_PVPP_DEF at (B 3) is labeled only once in the design.
Signal VR_PVPP_DEF_ISET at (A 3) is labeled only once in the design.
Signal VR_PVPP_DEF_PHASE at (B 2) is labeled only once in the design.
Signal VR_FET_SW_P12V_STBY_PVPP_DEF at (B 3) is labeled only once in the design.

Warnings in Page : @baseboard_fab2_lib.baseboard_fab2(sch_1):Page233
Signal  VR_FB_PVPP_GHJ at (A 1) is labeled only once in the design.
Signal  VR_VB_PVPP_GHJ at (B 3) is labeled only once in the design.
Signal VR_COMP_PVPP_GHJ_3 at (B 2) is labeled only once in the design.
Signal VR_COMP_PVPP_GHJ at (A 1) is labeled only once in the design.
Signal VSENSE_PVPP_GHJ at (A 1) is labeled only once in the design.
Signal VR_PVPP_GHJ_BOOT at (B 2) is labeled only once in the design.
Signal VR_PVPP_GHJ_PHASE at (B 2) is labeled only once in the design.
Signal VR_PVPP_GHJ_BOOT_R at (B 2) is labeled only once in the design.
Signal VR_PVPP_GHJ_SNUB at (B 2) is labeled only once in the design.
Signal VR_COMP_RC_PVPP_GHJ at (A 2) is labeled only once in the design.
Signal  VR_PVPP_GHJ_SS at (A 3) is labeled only once in the design.
Signal PWRGD_PVPP_GHJ_R at (A 2) is labeled only once in the design.
Signal VR_PVPP_GHJ_ISET at (A 3) is labeled only once in the design.
Signal FM_PVPP_PVDDQ_CPU1_EN_GHJ at (B 3) is labeled only once in the design.
Signal VR_FET_SW_P12V_STBY_PVPP_GHJ at (B 3) is labeled only once in the design.

Warnings in Page : @baseboard_fab2_lib.baseboard_fab2(sch_1):Page234
Signal  VR_FB_PVPP_KLM at (A 1) is labeled only once in the design.
Signal VR_PVPP_KLM_SNUB at (B 2) is labeled only once in the design.
Signal VR_PVPP_KLM_PHASE at (B 2) is labeled only once in the design.
Signal VR_PVPP_KLM_BOOT_R at (B 2) is labeled only once in the design.
Signal VR_COMP_PVPP_KLM_3 at (B 2) is labeled only once in the design.
Signal VSENSE_PVPP_KLM at (A 1) is labeled only once in the design.
Signal VR_COMP_PVPP_KLM at (A 1) is labeled only once in the design.
Signal VR_COMP_RC_PVPP_KLM at (B 2) is labeled only once in the design.
Signal VR_FET_SW_P12V_STBY_PVPP_KLM at (B 3) is labeled only once in the design.
Signal VR_PVPP_KLM_BOOT at (B 2) is labeled only once in the design.
Signal PWRGD_PVPP_KLM_R at (A 2) is labeled only once in the design.
Signal  VR_PVPP_KLM_SS at (A 3) is labeled only once in the design.
Signal  VR_VB_PVPP_KLM at (B 3) is labeled only once in the design.
Signal FM_PVPP_PVDDQ_CPU1_EN_KLM at (B 3) is labeled only once in the design.
Signal VR_PVPP_KLM_ISET at (A 3) is labeled only once in the design.

Warnings in Page : @baseboard_fab2_lib.baseboard_fab2(sch_1):Page235
Signal PU_PVNN_PCH_PINALRT_N at (B 2) is labeled only once in the design.
Signal VR_PVNN_PCH_XADDR2 at (A 3) is labeled only once in the design.
Signal VR_PVNN_PCH_VDD at (B 3) is labeled only once in the design.
Signal PWRGD_PVNN_PCH_R at (B 2) is labeled only once in the design.
Signal IRQ_PVNN_PCH_VRHOT_N at (B 2) is labeled only once in the design.
Signal PU_VR_PVNN_PCH_FAULT1 at (B 2) is labeled only once in the design.
Signal PU_PVNN_PCH_VDIO at (B 3) is labeled only once in the design.
Signal VR_PVNN_PCH_VREN at (B 3) is labeled only once in the design.
Signal VR_P1V05_PCH_STBY_AVSP at (A 4) is labeled only once in the design.
Signal VR_PVNN_PCH_AVSP at (A 4) is labeled only once in the design.
Signal PU_PVNN_PCH_VCLK at (B 3) is labeled only once in the design.
Signal VR_PVNN_PCH_XADDR1 at (A 3) is labeled only once in the design.
Signal SMB_VR_STBY_LVC3_SCL at (A 4) has too little display space.

Warnings in Page : @baseboard_fab2_lib.baseboard_fab2(sch_1):Page236
Signal VR_PVNN_PCH_PH1_VCIN at (B 3) is labeled only once in the design.
Signal VR_PVNN_PCH_PH1_PHASE_SW_RC at (B 1) is labeled only once in the design.
Signal VR_PVNN_PCH_PH1_PHASE_SW at (B 2) is labeled only once in the design.
Signal VR_PVNN_PCH_PH1_BOOT at (B 4) is labeled only once in the design.
Signal VR_PVNN_PCH_PH1_PHASE at (B 4) is labeled only once in the design.
Signal TP_P1V05_PCH_GL_0 at (A 3) is labeled only once in the design.
Signal VR_P1V05_PCH_STBY_PH1_VCIN at (B 3) is labeled only once in the design.
Signal VR_P1V05_PCH_STBY_PH1_SW_RC at (A 2) is labeled only once in the design.
Signal VR_P1V05_PCH_STBY_PH1_PHASE_SW at (A 2) is labeled only once in the design.
Signal VR_P1V05_PCH_STBY_OCSET at (B 2) is labeled only once in the design.
Signal VR_P1V05_PCH_STBY_PH1_BOOT_R at (A 3) is labeled only once in the design.
Signal TP_P1V05_PCH_GL_1 at (A 3) is labeled only once in the design.
Signal VR_PVNN_PCH_STBY_OCSET at (B 2) is labeled only once in the design.
Signal TP_PVNN_PCH_GL_1 at (B 3) is labeled only once in the design.
Signal TP_PVNN_PCH_GL_0 at (B 3) is labeled only once in the design.
Signal VR_PVNN_PCH_PH1_BOOT_R at (B 3) is labeled only once in the design.
Signal VR_P1V05_PCH_STBY_PH1_BOOT at (A 4) is labeled only once in the design.
Signal VR_P1V05_PCH_STBY_PH1_PHASE at (A 4) is labeled only once in the design.

Warnings in Page : @baseboard_fab2_lib.baseboard_fab2(sch_1):Page237
Signal PWRGD_P1V8_PCH_STBY_R at (B 2) is labeled only once in the design.
Signal VR_P1V8_PCH_STBY_FB at (A 2) is labeled only once in the design.

Warnings in Page : @baseboard_fab2_lib.baseboard_fab2(sch_1):Page238
Signal PWRGD_P1V15_BMC_STBY_R at (B 2) is labeled only once in the design.
Signal VR_P1V15_BMC_STBY_FB at (A 2) is labeled only once in the design.

Warnings in Page : @baseboard_fab2_lib.baseboard_fab2(sch_1):Page239
Signal VR_P2V5_BMC_STBY_FB at (A 2) is labeled only once in the design.
Signal VR_P1V2_BMC_STBY_FB at (B 2) is labeled only once in the design.
Signal PWRGD_P2V5_BMC_STBY_R at (A 2) is labeled only once in the design.
Signal PWRGD_P1V2_BMC_STBY_R at (B 2) is labeled only once in the design.

Warnings in Page : @baseboard_fab2_lib.baseboard_fab2(sch_1):Page240
Signal VR_P3V3_STBY_SNUB at (B 2) is labeled only once in the design.
Signal VR_P3V3_STBY_UGATE at (B 3) is labeled only once in the design.
Signal VR_P3V3_STBY_LGATE at (A 3) is labeled only once in the design.
Signal VR_FET_SW_P12V_STBY_P3V3_STBY at (B 3) is labeled only once in the design.
Signal VSENSE_P3V3_STBY at (A 2) is labeled only once in the design.
Signal VR_P3V3_STBY_EN at (B 4) is labeled only once in the design.
Signal VSENSE_VOUT_P3V3_STBY at (A 3) is labeled only once in the design.
Signal VSENSE_RGND_P3V3_STBY at (A 3) is labeled only once in the design.
Signal VR_P3V3_STBY_BOOT_R at (B 3) is labeled only once in the design.
Signal PWRGD_P3V3_STBY_R at (B 4) is labeled only once in the design.
Signal VR_P3V3_STBY_OCSELECT at (A 4) is labeled only once in the design.
Signal VR_P3V3_STBY_BOOT at (B 3) is labeled only once in the design.
Signal VR_P3V3_STBY_PHASE at (B 2) is labeled only once in the design.

Warnings in Page : @baseboard_fab2_lib.baseboard_fab2(sch_1):Page241
Signal VR_P5V_STBY_PHASE at (B 2) is labeled only once in the design.
Signal PWRGD_P5V_STBY_R at (B 2) is labeled only once in the design.
Signal VR_FET_SW_P5V_STBY_PVIN at (B 3) is labeled only once in the design.
Signal VR_P5V_STBY_VIN at (B 3) is labeled only once in the design.
Signal  VR_P5V_STBY_RT at (B 3) is labeled only once in the design.
Signal  VR_P5V_STBY_EN at (B 3) is labeled only once in the design.
Signal VR_P5V_STBY_VSENSE_R at (B 2) is labeled only once in the design.
Signal VR_P5V_STBY_BOOT at (B 2) is labeled only once in the design.
Signal VR_P5V_STBY_VSENSE at (B 2) is labeled only once in the design.
Signal VR_P5V_STBY_RC_COMP at (A 3) is labeled only once in the design.
Signal  VR_P5V_STBY_SS at (B 3) is labeled only once in the design.
Signal VR_P5V_STBY_COMP at (A 3) is labeled only once in the design.

Warnings in Page : @baseboard_fab2_lib.baseboard_fab2(sch_1):Page245
Signal  JTAG_RISER_TDI at (B 3) is labeled only once in the design.
Signal  JTAG_RISER_TDO at (B 3) is labeled only once in the design.
Signal  JTAG_RISER_TCK at (B 2) is labeled only once in the design.
Signal  JTAG_RISER_TMS at (B 2) is labeled only once in the design.
Signal JTAG_RISER_TRST at (B 2) is labeled only once in the design.

Warnings in Page : @baseboard_fab2_lib.baseboard_fab2(sch_1):Page246
Signal SPI_TPM_BMC_DI_R at (B 3) is labeled only once in the design.
Signal    TP_TPM_SPI_0 at (B 2) is labeled only once in the design.
Signal    TP_TPM_SPI_1 at (B 2) is labeled only once in the design.
Signal PU_TPM_SPI_FLASH_RESET_2_N at (A 3) is labeled only once in the design.
Signal PU_TPM_SPI_BMC_HOLD_N at (B 3) is labeled only once in the design.
Signal    TP_TPM_SPI_5 at (B 2) is labeled only once in the design.
Signal    TP_TPM_SPI_6 at (B 2) is labeled only once in the design.
Signal    TP_TPM_SPI_2 at (B 2) is labeled only once in the design.
Signal    TP_TPM_SPI_3 at (B 2) is labeled only once in the design.
Signal    TP_TPM_SPI_4 at (B 2) is labeled only once in the design.

Warnings in Page : @baseboard_fab2_lib.baseboard_fab2(sch_1):Page247
Signal SMB_HOST_STBY_LVC3_SCL_R3 at (A 2) is labeled only once in the design.
Signal PU_ID_EEPROM_A0 at (A 2) is labeled only once in the design.
Signal SMB_HOST_STBY_LVC3_SDA_R3 at (A 1) is labeled only once in the design.
Signal PD_ID_EEPROM_WP at (A 2) is labeled only once in the design.
Signal FM_CPU_CATERR_MSMI_LVT3_N at (B 2) is labeled only once in the design.
Signal SMB_BMC_PMBUS_STBY_LVC3_SDA at (A 3) has too little display space.
Signal SMB_HOST_STBY_LVC3_SDA at (A 1) has too little display space.

Warnings in Page : @baseboard_fab2_lib.baseboard_fab2(sch_1):Page248
Signal TP_SMB_PEHPCPU0_EN at (B 2) is labeled only once in the design.
Signal SMB_CPU0_PE_HP_GTL_R_SDA at (B 3) is labeled only once in the design.
Signal RST_PCIE_M2_DEV_AND at (A 2) is labeled only once in the design.
Signal SMB_CPU0_PE_HP_GTL_R_SCL at (B 3) is labeled only once in the design.

Warnings in Page : @baseboard_fab2_lib.baseboard_fab2(sch_1):Page249
Signal BMC_TPM_HW_C_RST at (A 3) is labeled only once in the design.
Signal BMC_SELF_HW_D_RST at (B 4) is labeled only once in the design.
Signal        VREF_2V2 at (B 2) is labeled only once in the design.
Signal FM_TPM_PRES_RST at (B 2) is labeled only once in the design.
Signal FM_TPM_PRES_RST_N_R at (B 3) is labeled only once in the design.

Warnings in Page : @baseboard_fab2_lib.baseboard_fab2(sch_1):Page251
Signal    PUMP_TACH1_R at (A 2) is labeled only once in the design.
Signal     PUMP_TACH_R at (B 2) is labeled only once in the design.
Signal       P12V_PUMP at (B 2) is labeled only once in the design.
Signal     PUMP_TACH_D at (B 2) is labeled only once in the design.
Signal         TP_PUMP at (B 1) is labeled only once in the design.
Signal  PUMP_PWM_OUT_R at (A 3) is labeled only once in the design.
Signal PUMP_PWM_OUT_BUF at (A 3) is labeled only once in the design.
Signal    PUMP_TACH1_D at (A 2) is labeled only once in the design.

Warnings in Page : @baseboard_fab2_lib.baseboard_fab2(sch_1):Page252
Signal VGA_REAR_VSYNC_S at (B 2) is labeled only once in the design.
Signal VGA_REAR_HSYNC_S at (B 2) is labeled only once in the design.
Signal I2C_BMC_VGA_DDC_SCL_G at (B 4) is labeled only once in the design.
Signal      Q25W1_GATE at (B 4) is labeled only once in the design.
Signal I2C_BMC_VGA_DDC_SDA_G at (A 4) is labeled only once in the design.
Signal      Q25W2_GATE at (A 4) is labeled only once in the design.

Warnings in Page : @baseboard_fab2_lib.baseboard_fab2(sch_1):Page253
Signal  USB3_P01_C_TXP at (A 3) is labeled only once in the design.
Signal  USB3_P01_C_TXN at (A 3) is labeled only once in the design.
Signal USB3_P01_FB_TXP at (A 3) is labeled only once in the design.
Signal USB3_P01_FB_RXN at (B 3) is labeled only once in the design.
Signal USB3_P01_FB_TXN at (A 3) is labeled only once in the design.
Signal USB3_P01_FB_RXP at (B 3) is labeled only once in the design.
Signal   P5V_STBY_USBC at (B 3) is labeled only once in the design.

Warnings in Page : @baseboard_fab2_lib.baseboard_fab2(sch_1):Page254
Signal JTAG_BMC_TCK_BUF at (A 3) is labeled only once in the design.
Signal JTAG_BMC_TRST_BUF_N at (A 2) is labeled only once in the design.
Signal  XDP_CPU_TCK0_R at (A 2) is labeled only once in the design.
Signal  XDP_PCH_TCK1_R at (A 2) is labeled only once in the design.
Signal    XDP_TRST_R_N at (A 2) is labeled only once in the design.
Signal PU_GTL2014_3_DIR at (B 3) is labeled only once in the design.
Signal       XDP_TMS_R at (B 2) is labeled only once in the design.
Signal       XDP_TDI_R at (B 2) is labeled only once in the design.
Signal PD_GTL2014_3_VREF at (B 3) is labeled only once in the design.

Warnings in Page : @baseboard_fab2_lib.baseboard_fab2(sch_1):Page255
Signal JTAG_BMC_BUF_TDO_R at (B 3) is labeled only once in the design.
Signal PD_GTL2014_DIR_6 at (B 3) is labeled only once in the design.
Signal TP_GTL2014_6_A0 at (B 3) is labeled only once in the design.
Signal PD_GTL2014_6_B2 at (B 4) is labeled only once in the design.
Signal P0V7_GTL2014_VREF_6 at (B 3) is labeled only once in the design.
Signal    BMC_JTAG_SEL at (A 2) is labeled only once in the design.
Signal TP_GTL2014_6_A2 at (B 3) is labeled only once in the design.
Signal PD_GTL2014_6_B0 at (B 4) is labeled only once in the design.

Warnings in Page : @baseboard_fab2_lib.baseboard_fab2(sch_1):Page256
Signal L10_100OHM_6INCH_DP at (B 1) is labeled only once in the design.
Signal L1_95OHM_6INCH_DP at (B 2) is labeled only once in the design.
Signal L14_100OHM_6INCH_DP at (B 1) is labeled only once in the design.
Signal L12_100OHM_6INCH_DN at (B 1) is labeled only once in the design.
Signal L12_100OHM_6INCH_DP at (B 1) is labeled only once in the design.
Signal L10_100OHM_6INCH_DN at (B 1) is labeled only once in the design.
Signal L1_100OHM_6INCH_DN at (B 1) is labeled only once in the design.
Signal L1_100OHM_6INCH_DP at (B 1) is labeled only once in the design.
Signal L5_85OHM_6INCH_DN at (B 3) is labeled only once in the design.
Signal L5_85OHM_6INCH_DP at (B 3) is labeled only once in the design.
Signal L1_85OHM_6INCH_DN at (B 3) is labeled only once in the design.
Signal L1_85OHM_6INCH_DP at (B 3) is labeled only once in the design.
Signal L3_85OHM_6INCH_DN at (B 3) is labeled only once in the design.
Signal L3_85OHM_6INCH_DP at (B 3) is labeled only once in the design.
Signal L10_85OHM_6INCH_DP at (B 3) is labeled only once in the design.
Signal L10_73OHM_6INCH_DP at (B 2) is labeled only once in the design.
Signal L5_73OHM_6INCH_DN at (B 2) is labeled only once in the design.
Signal L5_73OHM_6INCH_DP at (B 2) is labeled only once in the design.
Signal L1_73OHM_6INCH_DN at (B 2) is labeled only once in the design.
Signal L1_73OHM_6INCH_DP at (B 2) is labeled only once in the design.
Signal L12_85OHM_6INCH_DN at (B 3) is labeled only once in the design.
Signal L14_85OHM_6INCH_DP at (B 3) is labeled only once in the design.
Signal L14_85OHM_6INCH_DN at (B 3) is labeled only once in the design.
Signal L14_73OHM_6INCH_DP at (B 2) is labeled only once in the design.
Signal L12_85OHM_6INCH_DP at (B 3) is labeled only once in the design.
Signal L10_85OHM_6INCH_DN at (B 3) is labeled only once in the design.
Signal L14_73OHM_6INCH_DN at (B 2) is labeled only once in the design.
Signal L12_73OHM_6INCH_DN at (B 2) is labeled only once in the design.
Signal L10_73OHM_6INCH_DN at (B 2) is labeled only once in the design.
Signal L14_40OHM_6INCH at (A 3) is labeled only once in the design.
Signal L12_40OHM_6INCH at (A 3) is labeled only once in the design.
Signal L10_40OHM_6INCH at (A 3) is labeled only once in the design.
Signal  L5_40OHM_6INCH at (A 4) is labeled only once in the design.
Signal  L1_40OHM_6INCH at (A 4) is labeled only once in the design.
Signal L10_50OHM_6INCH at (A 1) is labeled only once in the design.
Signal  L3_50OHM_6INCH at (A 2) is labeled only once in the design.
Signal  L5_50OHM_6INCH at (A 2) is labeled only once in the design.
Signal  L3_40OHM_6INCH at (A 4) is labeled only once in the design.
Signal L12_50OHM_6INCH at (A 1) is labeled only once in the design.
Signal L12_73OHM_6INCH_DP at (B 2) is labeled only once in the design.
Signal L12_95OHM_6INCH_DP at (B 1) is labeled only once in the design.
Signal L3_73OHM_6INCH_DN at (B 2) is labeled only once in the design.
Signal L3_73OHM_6INCH_DP at (B 2) is labeled only once in the design.
Signal L14_100OHM_6INCH_DN at (B 1) is labeled only once in the design.
Signal L14_50OHM_6INCH at (A 1) is labeled only once in the design.
Signal  L1_50OHM_6INCH at (A 2) is labeled only once in the design.
Signal L12_95OHM_6INCH_DN at (B 1) is labeled only once in the design.
Signal L1_95OHM_6INCH_DN at (B 2) is labeled only once in the design.

Warnings in Page : @baseboard_fab2_lib.baseboard_fab2(sch_1):Page257
Signal L10_85OHM_5INCH_DN at (B 3) has too little display space.
Signal L10_85OHM_5INCH_DP at (B 3) has too little display space.
Signal L10_85OHM_5INCH_DN at (B 3) has too little display space.
Signal L10_85OHM_5INCH_DP at (B 3) has too little display space.
Signal L5_85OHM_5INCH_DP at (B 4) has too little display space.
Signal L5_85OHM_5INCH_DN at (B 4) has too little display space.
Signal L3_85OHM_5INCH_DP at (B 4) has too little display space.
Signal L3_85OHM_5INCH_DN at (B 4) has too little display space.
Signal L1_85OHM_5INCH_DP at (B 4) has too little display space.
Signal L1_85OHM_5INCH_DN at (B 4) has too little display space.
Signal L1_85OHM_5INCH_DP at (B 4) has too little display space.
Signal L3_85OHM_5INCH_DN at (B 4) has too little display space.
Signal L3_85OHM_5INCH_DP at (B 4) has too little display space.
Signal L5_85OHM_5INCH_DN at (B 4) has too little display space.
Signal L5_85OHM_5INCH_DP at (B 4) has too little display space.
Signal L12_85OHM_5INCH_DN at (B 3) has too little display space.
Signal L12_85OHM_5INCH_DP at (B 3) has too little display space.
Signal L12_85OHM_5INCH_DN at (B 3) has too little display space.
Signal L12_85OHM_5INCH_DP at (B 3) has too little display space.
Signal L14_85OHM_5INCH_DN at (B 3) has too little display space.
Signal L14_85OHM_5INCH_DN at (B 3) has too little display space.
Signal L14_85OHM_5INCH_DP at (B 3) has too little display space.
Signal L14_85OHM_5INCH_DP at (B 3) has too little display space.
Signal L1_85OHM_5INCH_DN at (B 4) has too little display space.

Warnings in Page : @baseboard_fab2_lib.baseboard_fab2(sch_1):Page258
Signal L1_85OHM_10INCH_DP at (B 3) has too little display space.
Signal L1_85OHM_10INCH_DN at (B 3) has too little display space.
Signal L1_85OHM_10INCH_DN at (B 3) has too little display space.
Signal L1_85OHM_10INCH_DP at (B 3) has too little display space.
Signal L3_85OHM_10INCH_DP at (B 3) has too little display space.
Signal L3_85OHM_10INCH_DN at (B 3) has too little display space.
Signal L3_85OHM_10INCH_DN at (B 3) has too little display space.
Signal L3_85OHM_10INCH_DP at (B 3) has too little display space.
Signal L5_85OHM_10INCH_DP at (A 3) has too little display space.
Signal L5_85OHM_10INCH_DN at (A 3) has too little display space.
Signal L5_85OHM_10INCH_DN at (A 3) has too little display space.
Signal L5_85OHM_10INCH_DP at (A 3) has too little display space.
Signal L10_85OHM_10INCH_DP at (B 2) has too little display space.
Signal L10_85OHM_10INCH_DN at (B 2) has too little display space.
Signal L10_85OHM_10INCH_DN at (B 2) has too little display space.
Signal L10_85OHM_10INCH_DP at (B 2) has too little display space.
Signal L12_85OHM_10INCH_DP at (B 2) has too little display space.
Signal L12_85OHM_10INCH_DN at (B 2) has too little display space.
Signal L12_85OHM_10INCH_DN at (B 2) has too little display space.
Signal L12_85OHM_10INCH_DP at (B 2) has too little display space.
Signal L14_85OHM_10INCH_DP at (A 2) has too little display space.
Signal L14_85OHM_10INCH_DN at (A 2) has too little display space.
Signal L14_85OHM_10INCH_DN at (A 2) has too little display space.
Signal L14_85OHM_10INCH_DP at (A 2) has too little display space.
